FILE_TYPE = MACRO_DRAWING;
SET COLOR_WIRE YELLOW;
SET COLOR_PROP ORANGE;
SET COLOR_DOT WHITE;
SET COLOR_ARC YELLOW;
SET COLOR_BODY GREEN;
SET COLOR_NOTE PURPLE;
SET PROP_DISPLAY VALUE;
SET PAGE_NUMBER P22;
SET PATH_NUMBER P107;
FORCEADD Q_RES..1
(-2025 4200);
FORCEPROP 1 LAST PACK_TYPE 0402LF
J 0
(-1775 4050);
DISPLAY 0.978723 (-1775 4050);
FORCEPROP 1 LAST PART_NUMBER CS00002JB13
J 0
(-2075 4300);
DISPLAY 0.978723 (-2075 4300);
FORCEPROP 1 LAST VALUE 0
J 2
(-2050 4100);
DISPLAY 0.978723 (-2050 4100);
FORCEPROP 1 LAST WATTAGE 1/16W
J 2
(-2050 4050);
DISPLAY 0.978723 (-2050 4050);
FORCEPROP 1 LAST MATERIAL CHIP
J 0
(-2025 4050);
DISPLAY 0.978723 (-2025 4050);
FORCEPROP 1 LAST TOLERANCE 5%
J 0
(-2025 4100);
DISPLAY 0.978723 (-2025 4100);
FORCEPROP 2 LAST CDS_LIB pure_quanta
J 0
(-2025 4200);
DISPLAY INVISIBLE (-2025 4200);
FORCEPROP 1 LAST PATH I10
J 0
(-2075 4350);
DISPLAY 0.978723 (-2075 4350);
PAINT WHITE (-2075 4350);
DISPLAY INVISIBLE (-2075 4350);
FORCEPROP 1 LAST LOCATION R636
J 0
(-2075 4250);
DISPLAY 0.978723 (-2075 4250);
FORCEPROP 1 LASTPIN (-2125 4200) $PN 1
J 0
(-2113 4212);
DISPLAY 0.787234 (-2113 4212);
PAINT MONO (-2113 4212);
FORCEPROP 1 LASTPIN (-1925 4200) $PN 2
J 0
(-1963 4212);
DISPLAY 0.787234 (-1963 4212);
PAINT MONO (-1963 4212);
FORCEPROP 0 LAST $SEC 1
J 0
(-2075 4350);
DISPLAY 0.680851 (-2075 4350);
PAINT MONO (-2075 4350);
DISPLAY INVISIBLE (-2075 4350);
FORCEPROP 0 LAST CDS_SEC 1
J 0
(-2075 4350);
DISPLAY 0.680851 (-2075 4350);
DISPLAY INVISIBLE (-2075 4350);
FORCEADD Q_RES..2
(-3700 2350);
FORCEPROP 1 LAST MATERIAL CHIP
J 0
(-3650 2275);
DISPLAY 0.787234 (-3650 2275);
FORCEPROP 1 LAST VALUE 0
J 0
(-3640 2325);
DISPLAY 0.787234 (-3640 2325);
FORCEPROP 1 LAST PART_NUMBER CS00002JB13
J 0
(-3650 2225);
DISPLAY 0.787234 (-3650 2225);
FORCEPROP 1 LAST TOLERANCE 5%
J 0
(-3655 2375);
DISPLAY 0.978723 (-3655 2375);
DISPLAY INVISIBLE (-3655 2375);
FORCEPROP 1 LAST PACK_TYPE 0402LF
J 0
(-3660 2175);
DISPLAY 0.978723 (-3660 2175);
DISPLAY INVISIBLE (-3660 2175);
FORCEPROP 1 LAST WATTAGE 1/16W
J 0
(-3660 2325);
DISPLAY 0.978723 (-3660 2325);
DISPLAY INVISIBLE (-3660 2325);
FORCEPROP 1 LAST PATH I100
J 0
(-3650 2525);
DISPLAY 0.978723 (-3650 2525);
PAINT WHITE (-3650 2525);
DISPLAY INVISIBLE (-3650 2525);
FORCEPROP 2 LAST CDS_LIB pure_quanta
J 0
(-3700 2350);
DISPLAY INVISIBLE (-3700 2350);
FORCEPROP 1 LAST LOCATION R282
J 0
(-3640 2375);
DISPLAY 0.787234 (-3640 2375);
FORCEPROP 1 LASTPIN (-3700 2450) $PN 1
J 0
(-3695 2412);
DISPLAY 0.787234 (-3695 2412);
PAINT MONO (-3695 2412);
FORCEPROP 1 LASTPIN (-3700 2250) $PN 2
J 0
(-3695 2260);
DISPLAY 0.787234 (-3695 2260);
PAINT MONO (-3695 2260);
FORCEPROP 0 LAST $SEC 1
J 0
(-3625 2425);
DISPLAY 0.680851 (-3625 2425);
PAINT MONO (-3625 2425);
DISPLAY INVISIBLE (-3625 2425);
FORCEPROP 0 LAST CDS_SEC 1
J 0
(-3625 2425);
DISPLAY 0.680851 (-3625 2425);
DISPLAY INVISIBLE (-3625 2425);
FORCEADD Q_RES..2
(-3700 2750);
FORCEPROP 1 LAST PART_NUMBER CS00002JB13
J 0
(-4110 2650);
DISPLAY 0.787234 (-4110 2650);
FORCEPROP 1 LAST VALUE 0
J 0
(-3800 2750);
DISPLAY 0.787234 (-3800 2750);
FORCEPROP 1 LAST MATERIAL CHIP
J 0
(-3900 2700);
DISPLAY 0.787234 (-3900 2700);
FORCEPROP 2 LAST CDS_LIB pure_quanta
J 0
(-3700 2750);
DISPLAY INVISIBLE (-3700 2750);
FORCEPROP 1 LAST PATH I101
J 0
(-3650 2925);
DISPLAY 0.978723 (-3650 2925);
PAINT WHITE (-3650 2925);
DISPLAY INVISIBLE (-3650 2925);
FORCEPROP 1 LAST TOLERANCE 5%
J 0
(-3655 2775);
DISPLAY 0.978723 (-3655 2775);
DISPLAY INVISIBLE (-3655 2775);
FORCEPROP 1 LAST PACK_TYPE 0402LF
J 0
(-3660 2575);
DISPLAY 0.978723 (-3660 2575);
DISPLAY INVISIBLE (-3660 2575);
FORCEPROP 1 LAST WATTAGE 1/16W
J 0
(-3660 2725);
DISPLAY 0.978723 (-3660 2725);
DISPLAY INVISIBLE (-3660 2725);
FORCEPROP 1 LAST LOCATION R450
J 0
(-3875 2800);
DISPLAY 0.787234 (-3875 2800);
FORCEPROP 1 LASTPIN (-3700 2850) $PN 1
J 0
(-3695 2812);
DISPLAY 0.787234 (-3695 2812);
PAINT MONO (-3695 2812);
FORCEPROP 1 LASTPIN (-3700 2650) $PN 2
J 0
(-3695 2660);
DISPLAY 0.787234 (-3695 2660);
PAINT MONO (-3695 2660);
FORCEPROP 0 LAST $SEC 1
J 0
(-3875 2850);
DISPLAY 0.680851 (-3875 2850);
PAINT MONO (-3875 2850);
DISPLAY INVISIBLE (-3875 2850);
FORCEPROP 0 LAST CDS_SEC 1
J 0
(-3875 2850);
DISPLAY 0.680851 (-3875 2850);
DISPLAY INVISIBLE (-3875 2850);
FORCEADD Q_RES..2
(-3750 3275);
FORCEPROP 1 LAST PACK_TYPE 0402LF
J 0
(-3725 3150);
DISPLAY 0.510638 (-3725 3150);
PAINT SKYBLUE (-3725 3150);
FORCEPROP 1 LAST MATERIAL EMPTY
J 0
(-3710 3200);
DISPLAY 0.510638 (-3710 3200);
PAINT RED (-3710 3200);
FORCEPROP 1 LAST WATTAGE 1/16W
J 0
(-3710 3250);
DISPLAY 0.510638 (-3710 3250);
PAINT SKYBLUE (-3710 3250);
FORCEPROP 1 LAST TOLERANCE 1%
J 0
(-3705 3300);
DISPLAY 0.510638 (-3705 3300);
PAINT SKYBLUE (-3705 3300);
FORCEPROP 1 LAST VALUE 1K
J 0
(-3705 3350);
DISPLAY 0.510638 (-3705 3350);
PAINT SKYBLUE (-3705 3350);
FORCEPROP 2 LAST CDS_LIB pure_quanta
J 0
(-3750 3275);
DISPLAY INVISIBLE (-3750 3275);
FORCEPROP 1 LAST PATH I102
J 0
(-3700 3450);
DISPLAY 0.978723 (-3700 3450);
PAINT WHITE (-3700 3450);
DISPLAY INVISIBLE (-3700 3450);
FORCEPROP 1 LAST PART_NUMBER CS21002FB06
J 0
(-3710 3150);
DISPLAY 0.510638 (-3710 3150);
PAINT WHITE (-3710 3150);
DISPLAY INVISIBLE (-3710 3150);
FORCEPROP 1 LAST $LOCATION R888
J 0
(-3705 3400);
DISPLAY 0.702128 (-3705 3400);
PAINT YELLOW (-3705 3400);
FORCEPROP 1 LASTPIN (-3750 3375) $PN 1
J 0
(-3745 3337);
DISPLAY 0.787234 (-3745 3337);
PAINT MONO (-3745 3337);
FORCEPROP 1 LASTPIN (-3750 3175) $PN 2
J 0
(-3745 3185);
DISPLAY 0.787234 (-3745 3185);
PAINT MONO (-3745 3185);
FORCEPROP 0 LAST CDS_LOCATION R888
J 0
(-3700 3450);
DISPLAY 0.680851 (-3700 3450);
DISPLAY INVISIBLE (-3700 3450);
FORCEPROP 0 LAST $SEC 1
J 0
(-3700 3450);
DISPLAY 0.680851 (-3700 3450);
PAINT MONO (-3700 3450);
DISPLAY INVISIBLE (-3700 3450);
FORCEPROP 0 LAST CDS_SEC 1
J 0
(-3700 3450);
DISPLAY 0.680851 (-3700 3450);
DISPLAY INVISIBLE (-3700 3450);
FORCEADD UNIVERSAL_POWER..1
(-3750 3475);
FORCEPROP 3 LASTPIN (-3750 3425) SIG_NAME P3V3_AUX\g
J 0
(-3740 3435);
DISPLAY 0.659574 (-3740 3435);
PAINT MONO (-3740 3435);
DISPLAY INVISIBLE (-3740 3435);
FORCEPROP 1 LAST HDL_POWER P3V3_AUX
J 1
(-3750 3525);
DISPLAY 0.702128 (-3750 3525);
PAINT GREEN (-3750 3525);
FORCEPROP 2 LAST CDS_LIB logical_power
J 0
(-3750 3475);
DISPLAY INVISIBLE (-3750 3475);
FORCEPROP 1 LAST PATH I103
J 0
(-3700 3500);
DISPLAY 0.872340 (-3700 3500);
PAINT AQUA (-3700 3500);
DISPLAY INVISIBLE (-3700 3500);
FORCEADD UNIVERSAL_POWER..1
(-4000 2550);
FORCEPROP 3 LASTPIN (-4000 2500) SIG_NAME P3V3_AUX\g
J 0
(-3990 2510);
DISPLAY 0.659574 (-3990 2510);
PAINT MONO (-3990 2510);
DISPLAY INVISIBLE (-3990 2510);
FORCEPROP 1 LAST HDL_POWER P3V3_AUX
J 1
(-4000 2600);
DISPLAY 0.702128 (-4000 2600);
PAINT GREEN (-4000 2600);
FORCEPROP 2 LAST CDS_LIB logical_power
J 0
(-4000 2550);
DISPLAY INVISIBLE (-4000 2550);
FORCEPROP 1 LAST PATH I104
J 0
(-3950 2575);
DISPLAY 0.872340 (-3950 2575);
PAINT AQUA (-3950 2575);
DISPLAY INVISIBLE (-3950 2575);
FORCEADD Q_RES..2
(-4000 2375);
FORCEPROP 1 LAST MATERIAL EMPTY
J 2
(-3875 2300);
DISPLAY 0.510638 (-3875 2300);
PAINT SKYBLUE (-3875 2300);
FORCEPROP 1 LAST VALUE 4.7K
J 2
(-3875 2350);
DISPLAY 0.510638 (-3875 2350);
PAINT SKYBLUE (-3875 2350);
FORCEPROP 1 LAST PACK_TYPE 0402LF
J 2
(-4025 2225);
DISPLAY 0.510638 (-4025 2225);
PAINT SKYBLUE (-4025 2225);
DISPLAY INVISIBLE (-4025 2225);
FORCEPROP 1 LAST WATTAGE 1/16W
J 2
(-4025 2325);
DISPLAY 0.510638 (-4025 2325);
PAINT SKYBLUE (-4025 2325);
DISPLAY INVISIBLE (-4025 2325);
FORCEPROP 1 LAST TOLERANCE 1%
J 2
(-4025 2375);
DISPLAY 0.510638 (-4025 2375);
PAINT SKYBLUE (-4025 2375);
DISPLAY INVISIBLE (-4025 2375);
FORCEPROP 2 LAST CDS_LIB pure_quanta
J 0
(-4000 2375);
DISPLAY INVISIBLE (-4000 2375);
FORCEPROP 1 LAST PATH I106
J 0
(-3950 2550);
DISPLAY 0.978723 (-3950 2550);
PAINT WHITE (-3950 2550);
DISPLAY INVISIBLE (-3950 2550);
FORCEPROP 1 LAST PART_NUMBER CS24702FB06
J 0
(-3960 2250);
DISPLAY 0.510638 (-3960 2250);
PAINT WHITE (-3960 2250);
DISPLAY INVISIBLE (-3960 2250);
FORCEPROP 1 LAST $LOCATION R887
J 2
(-3850 2400);
DISPLAY 0.702128 (-3850 2400);
PAINT YELLOW (-3850 2400);
FORCEPROP 1 LASTPIN (-4000 2475) $PN 1
J 0
(-3995 2437);
DISPLAY 0.787234 (-3995 2437);
PAINT MONO (-3995 2437);
FORCEPROP 1 LASTPIN (-4000 2275) $PN 2
J 0
(-3995 2285);
DISPLAY 0.787234 (-3995 2285);
PAINT MONO (-3995 2285);
FORCEPROP 0 LAST CDS_LOCATION R887
J 0
(-3850 2450);
DISPLAY 0.680851 (-3850 2450);
DISPLAY INVISIBLE (-3850 2450);
FORCEPROP 0 LAST $SEC 1
J 0
(-3850 2450);
DISPLAY 0.680851 (-3850 2450);
PAINT MONO (-3850 2450);
DISPLAY INVISIBLE (-3850 2450);
FORCEPROP 0 LAST CDS_SEC 1
J 0
(-3850 2450);
DISPLAY 0.680851 (-3850 2450);
DISPLAY INVISIBLE (-3850 2450);
FORCEADD Q_CAP..1
(325 2550);
FORCEPROP 1 LAST PART_NUMBER TMP_QCH22206KB16
R 3
J 0
(225 2700);
DISPLAY 0.510638 (225 2700);
PAINT WHITE (225 2700);
FORCEPROP 1 LAST TOLERANCE 10%
J 0
(375 2500);
DISPLAY 0.510638 (375 2500);
PAINT SKYBLUE (375 2500);
FORCEPROP 1 LAST MATERIAL X7R
J 0
(375 2450);
DISPLAY 0.510638 (375 2450);
PAINT SKYBLUE (375 2450);
FORCEPROP 1 LAST PACK_TYPE 0402
J 0
(375 2400);
DISPLAY 0.510638 (375 2400);
PAINT SKYBLUE (375 2400);
FORCEPROP 1 LAST VOLTAGE 50V
J 0
(375 2550);
DISPLAY 0.510638 (375 2550);
PAINT SKYBLUE (375 2550);
FORCEPROP 1 LAST VALUE 2200PF
J 0
(350 2600);
DISPLAY 0.510638 (350 2600);
PAINT SKYBLUE (350 2600);
FORCEPROP 1 LAST PATH I107
J 0
(375 2700);
DISPLAY 0.978723 (375 2700);
PAINT WHITE (375 2700);
DISPLAY INVISIBLE (375 2700);
FORCEPROP 2 LAST CDS_LIB pure_quanta
J 0
(325 2550);
DISPLAY INVISIBLE (325 2550);
FORCEPROP 1 LAST LOCATION C173
J 0
(375 2650);
DISPLAY 0.702128 (375 2650);
PAINT YELLOW (375 2650);
FORCEPROP 1 LASTPIN (325 2650) $PN 1
J 0
(335 2630);
DISPLAY 0.787234 (335 2630);
PAINT MONO (335 2630);
FORCEPROP 1 LASTPIN (325 2450) $PN 2
J 0
(335 2430);
DISPLAY 0.787234 (335 2430);
PAINT MONO (335 2430);
FORCEPROP 0 LAST $SEC 1
J 0
(375 2700);
DISPLAY 0.680851 (375 2700);
PAINT MONO (375 2700);
DISPLAY INVISIBLE (375 2700);
FORCEPROP 0 LAST CDS_SEC 1
J 0
(375 2700);
DISPLAY 0.680851 (375 2700);
DISPLAY INVISIBLE (375 2700);
FORCEADD OFFPAGE..5
(-2825 4200);
FORCEPROP 2 LAST $XR1 34 
J 0
(-3139 4200);
DISPLAY 0.638298 (-3139 4200);
PAINT MONO (-3139 4200);
FORCEPROP 2 LAST $XR0 15 
J 0
(-3049 4200);
DISPLAY 0.638298 (-3049 4200);
PAINT MONO (-3049 4200);
FORCEPROP 2 LAST CDS_LIB standard
J 0
(-2825 4200);
DISPLAY 0.808511 (-2825 4200);
PAINT MONO (-2825 4200);
DISPLAY INVISIBLE (-2825 4200);
FORCEPROP 1 LAST OFFPAGE TRUE
J 0
(-2500 4075);
DISPLAY 0.872340 (-2500 4075);
PAINT GREEN (-2500 4075);
DISPLAY INVISIBLE (-2500 4075);
FORCEPROP 1 LAST COMMENT_BODY TRUE
J 0
(-2725 4125);
DISPLAY 0.872340 (-2725 4125);
PAINT PEACH (-2725 4125);
DISPLAY INVISIBLE (-2725 4125);
FORCEPROP 2 LAST PATH I11
J 0
(-3025 4250);
DISPLAY 0.680851 (-3025 4250);
DISPLAY INVISIBLE (-3025 4250);
FORCEADD Q_RES..1
(-2025 3650);
FORCEPROP 1 LAST MATERIAL EMPTY
J 0
(-2000 3550);
DISPLAY 0.978723 (-2000 3550);
FORCEPROP 1 LAST VALUE 0
J 2
(-2050 3550);
DISPLAY 0.978723 (-2050 3550);
FORCEPROP 1 LAST PART_NUMBER CS00002JB13
J 0
(-2075 3750);
DISPLAY 0.978723 (-2075 3750);
FORCEPROP 1 LAST TOLERANCE 5%
J 0
(-2025 3550);
DISPLAY 0.978723 (-2025 3550);
DISPLAY INVISIBLE (-2025 3550);
FORCEPROP 1 LAST PACK_TYPE 0402LF
J 0
(-1775 3500);
DISPLAY 0.978723 (-1775 3500);
DISPLAY INVISIBLE (-1775 3500);
FORCEPROP 1 LAST WATTAGE 1/16W
J 2
(-2050 3500);
DISPLAY 0.978723 (-2050 3500);
DISPLAY INVISIBLE (-2050 3500);
FORCEPROP 1 LAST PATH I12
J 0
(-2075 3800);
DISPLAY 0.978723 (-2075 3800);
PAINT WHITE (-2075 3800);
DISPLAY INVISIBLE (-2075 3800);
FORCEPROP 2 LAST CDS_LIB pure_quanta
J 0
(-2025 3650);
DISPLAY INVISIBLE (-2025 3650);
FORCEPROP 1 LAST LOCATION R106
J 0
(-2075 3700);
DISPLAY 0.978723 (-2075 3700);
FORCEPROP 1 LASTPIN (-2125 3650) $PN 1
J 0
(-2113 3662);
DISPLAY 0.787234 (-2113 3662);
PAINT MONO (-2113 3662);
FORCEPROP 1 LASTPIN (-1925 3650) $PN 2
J 0
(-1963 3662);
DISPLAY 0.787234 (-1963 3662);
PAINT MONO (-1963 3662);
FORCEPROP 0 LAST $SEC 1
J 0
(-2075 3800);
DISPLAY 0.680851 (-2075 3800);
PAINT MONO (-2075 3800);
DISPLAY INVISIBLE (-2075 3800);
FORCEPROP 0 LAST CDS_SEC 1
J 0
(-2075 3800);
DISPLAY 0.680851 (-2075 3800);
DISPLAY INVISIBLE (-2075 3800);
FORCEADD OFFPAGE..5
(-2825 3650);
FORCEPROP 2 LAST $XR1 22 
J 0
(-3139 3650);
DISPLAY 0.638298 (-3139 3650);
PAINT MONO (-3139 3650);
FORCEPROP 2 LAST $XR0 15 
J 0
(-3049 3650);
DISPLAY 0.638298 (-3049 3650);
PAINT MONO (-3049 3650);
FORCEPROP 2 LAST CDS_LIB standard
J 0
(-2825 3650);
DISPLAY 0.808511 (-2825 3650);
PAINT MONO (-2825 3650);
DISPLAY INVISIBLE (-2825 3650);
FORCEPROP 1 LAST OFFPAGE TRUE
J 0
(-2500 3525);
DISPLAY 0.872340 (-2500 3525);
PAINT GREEN (-2500 3525);
DISPLAY INVISIBLE (-2500 3525);
FORCEPROP 1 LAST COMMENT_BODY TRUE
J 0
(-2725 3575);
DISPLAY 0.872340 (-2725 3575);
PAINT PEACH (-2725 3575);
DISPLAY INVISIBLE (-2725 3575);
FORCEPROP 2 LAST PATH I13
J 0
(-3025 3700);
DISPLAY 0.680851 (-3025 3700);
DISPLAY INVISIBLE (-3025 3700);
FORCEADD MOSFET_N..1
(650 2875);
FORCEPROP 2 LAST MANUF_PN BSS138K
J 0
(800 2925);
DISPLAY 0.680851 (800 2925);
FORCEPROP 2 LAST PATH I14
J 0
(800 2875);
DISPLAY 0.680851 (800 2875);
FORCEPROP 1 LAST VALUE BSS138K
J 0
(797 2821);
DISPLAY 0.723404 (797 2821);
PAINT GREEN (797 2821);
FORCEPROP 1 LAST PART_NUMBER BAM138K0000
J 0
(797 2661);
DISPLAY 0.723404 (797 2661);
PAINT GREEN (797 2661);
FORCEPROP 1 LAST MATERIAL IC
J 0
(797 2581);
DISPLAY 0.723404 (797 2581);
PAINT GREEN (797 2581);
FORCEPROP 1 LAST PACK_TYPE SMLF
J 0
(675 2625);
DISPLAY 0.723404 (675 2625);
PAINT GREEN (675 2625);
DISPLAY INVISIBLE (675 2625);
FORCEPROP 2 LAST CDS_LIB pure_quanta
J 0
(650 2875);
DISPLAY INVISIBLE (650 2875);
FORCEPROP 1 LAST CDS_LMAN_SYM_OUTLINE -50,50,100,-150
J 0
(650 2875);
DISPLAY 0.468085 (650 2875);
PAINT GREEN (650 2875);
DISPLAY INVISIBLE (650 2875);
FORCEPROP 1 LAST LOCATION U12
J 0
(797 2741);
DISPLAY 0.723404 (797 2741);
PAINT GREEN (797 2741);
FORCEPROP 1 LASTPIN (700 2975) $PN D
R 1
J 0
(700 2968);
DISPLAY 0.659574 (700 2968);
PAINT MONO (700 2968);
FORCEPROP 1 LASTPIN (550 2775) $PN G
J 2
(560 2778);
DISPLAY 0.659574 (560 2778);
PAINT MONO (560 2778);
FORCEPROP 1 LASTPIN (700 2675) $PN S
R 1
J 2
(700 2688);
DISPLAY 0.659574 (700 2688);
PAINT MONO (700 2688);
FORCEPROP 0 LAST $SEC 1
J 0
(825 2800);
DISPLAY 0.680851 (825 2800);
PAINT MONO (825 2800);
DISPLAY INVISIBLE (825 2800);
FORCEPROP 0 LAST CDS_SEC 1
J 0
(825 2800);
DISPLAY 0.680851 (825 2800);
DISPLAY INVISIBLE (825 2800);
FORCEADD UNIVERSAL_POWER..1
(3700 2825);
FORCEPROP 3 LASTPIN (3700 2775) SIG_NAME P3V3_AUX\g
J 0
(3710 2785);
DISPLAY 0.659574 (3710 2785);
PAINT MONO (3710 2785);
DISPLAY INVISIBLE (3710 2785);
FORCEPROP 1 LAST HDL_POWER P3V3_AUX
J 1
(3700 2875);
DISPLAY 0.702128 (3700 2875);
PAINT GREEN (3700 2875);
FORCEPROP 1 LAST PATH I16
J 0
(3750 2850);
DISPLAY 0.872340 (3750 2850);
PAINT AQUA (3750 2850);
DISPLAY INVISIBLE (3750 2850);
FORCEPROP 2 LAST CDS_LIB logical_power
J 0
(3700 2825);
DISPLAY INVISIBLE (3700 2825);
FORCEADD Q_CAP..1
(3875 2550);
FORCEPROP 1 LAST PACK_TYPE 0402
J 0
(3925 2350);
DISPLAY 0.510638 (3925 2350);
PAINT SKYBLUE (3925 2350);
FORCEPROP 1 LAST PART_NUMBER CH4104K1B00
J 0
(3925 2400);
DISPLAY 0.510638 (3925 2400);
PAINT WHITE (3925 2400);
FORCEPROP 1 LAST VALUE 0.1UF
J 0
(3925 2600);
DISPLAY 0.510638 (3925 2600);
PAINT SKYBLUE (3925 2600);
FORCEPROP 1 LAST TOLERANCE 10%
J 0
(3925 2500);
DISPLAY 0.510638 (3925 2500);
PAINT SKYBLUE (3925 2500);
FORCEPROP 1 LAST VOLTAGE 25V
J 0
(3925 2550);
DISPLAY 0.510638 (3925 2550);
PAINT SKYBLUE (3925 2550);
FORCEPROP 1 LAST MATERIAL EMPTY
J 0
(3925 2450);
DISPLAY 0.510638 (3925 2450);
PAINT SKYBLUE (3925 2450);
FORCEPROP 2 LAST CDS_LIB pure_quanta
J 0
(3875 2550);
DISPLAY INVISIBLE (3875 2550);
FORCEPROP 2 LAST SEC_TYPE 0402
J 0
(3925 2750);
DISPLAY 1.021277 (3925 2750);
DISPLAY INVISIBLE (3925 2750);
FORCEPROP 1 LAST PATH I17
J 0
(3925 2700);
DISPLAY 0.978723 (3925 2700);
PAINT WHITE (3925 2700);
DISPLAY INVISIBLE (3925 2700);
FORCEPROP 1 LAST LOCATION C147
J 0
(3925 2650);
DISPLAY 0.702128 (3925 2650);
PAINT YELLOW (3925 2650);
FORCEPROP 1 LASTPIN (3875 2650) $PN 1
J 0
(3885 2630);
DISPLAY 0.808511 (3885 2630);
PAINT WHITE (3885 2630);
FORCEPROP 1 LASTPIN (3875 2450) $PN 2
J 0
(3885 2430);
DISPLAY 0.808511 (3885 2430);
PAINT WHITE (3885 2430);
FORCEPROP 2 LAST SEC 1
J 0
(3925 2750);
DISPLAY 0.680851 (3925 2750);
PAINT MONO (3925 2750);
DISPLAY INVISIBLE (3925 2750);
FORCEADD UNIVERSAL_GND..1
(3875 2350);
FORCEPROP 3 LASTPIN (3875 2400) SIG_NAME GND\g
J 0
(3885 2410);
DISPLAY 0.659574 (3885 2410);
PAINT MONO (3885 2410);
DISPLAY INVISIBLE (3885 2410);
FORCEPROP 1 LAST PATH I18
J 0
(3950 2350);
DISPLAY 0.872340 (3950 2350);
PAINT AQUA (3950 2350);
DISPLAY INVISIBLE (3950 2350);
FORCEPROP 1 LAST HDL_POWER GND
J 1
(3900 2275);
DISPLAY 0.702128 (3900 2275);
PAINT GREEN (3900 2275);
DISPLAY INVISIBLE (3900 2275);
FORCEPROP 2 LAST CDS_LIB logical_power
J 0
(3875 2350);
DISPLAY INVISIBLE (3875 2350);
FORCEADD MMBT39047F..1
R 2
(-525 4025);
FORCEPROP 1 LAST PART_NUMBER BA0390400H0
J 2
(-601 3985);
DISPLAY 0.723404 (-601 3985);
PAINT GREEN (-601 3985);
FORCEPROP 2 LAST VALUE MMBT3904-7-F
J 2
(-600 4075);
DISPLAY 1.021277 (-600 4075);
FORCEPROP 1 LAST MATERIAL IC
J 2
(-601 3935);
DISPLAY 0.723404 (-601 3935);
PAINT GREEN (-601 3935);
FORCEPROP 2 LAST PART_TYPE SMLF
J 2
(-600 4125);
DISPLAY 1.021277 (-600 4125);
FORCEPROP 2 LAST SEC_TYPE 
J 0
(-600 4175);
DISPLAY 1.021277 (-600 4175);
DISPLAY INVISIBLE (-600 4175);
FORCEPROP 2 LAST CDS_LIB pure_quanta
J 2
(-525 4025);
DISPLAY INVISIBLE (-525 4025);
FORCEPROP 1 LAST NEEDS_NO_SIZE TRUE
J 2
(-575 3975);
DISPLAY 0.468085 (-575 3975);
PAINT GREEN (-575 3975);
DISPLAY INVISIBLE (-575 3975);
FORCEPROP 1 LAST CDS_LMAN_SYM_OUTLINE -50,50,50,-50
J 2
(-525 4025);
DISPLAY 0.468085 (-525 4025);
PAINT GREEN (-525 4025);
DISPLAY INVISIBLE (-525 4025);
FORCEPROP 1 LAST PATH I2
J 2
(-525 4025);
DISPLAY 0.723404 (-525 4025);
PAINT GREEN (-525 4025);
DISPLAY INVISIBLE (-525 4025);
FORCEPROP 1 LAST LOCATION Q1
J 2
(-594 4030);
DISPLAY 0.723404 (-594 4030);
PAINT GREEN (-594 4030);
FORCEPROP 0 LASTPIN (-425 4025) $PN B
J 0
(-415 4035);
DISPLAY 0.680851 (-415 4035);
PAINT MONO (-415 4035);
FORCEPROP 0 LASTPIN (-575 3925) $PN E
R 1
J 2
(-585 3915);
DISPLAY 0.680851 (-585 3915);
PAINT MONO (-585 3915);
FORCEPROP 0 LASTPIN (-575 4125) $PN C
R 1
J 0
(-585 4135);
DISPLAY 0.680851 (-585 4135);
PAINT MONO (-585 4135);
FORCEPROP 2 LAST SEC 1
J 0
(-600 4175);
DISPLAY 0.680851 (-600 4175);
PAINT MONO (-600 4175);
DISPLAY INVISIBLE (-600 4175);
FORCEADD UNIVERSAL_GND..1
(700 2300);
FORCEPROP 3 LASTPIN (700 2350) SIG_NAME GND\g
J 0
(710 2360);
DISPLAY 0.659574 (710 2360);
PAINT MONO (710 2360);
DISPLAY INVISIBLE (710 2360);
FORCEPROP 2 LAST CDS_LIB logical_power
J 0
(700 2300);
DISPLAY INVISIBLE (700 2300);
FORCEPROP 1 LAST HDL_POWER GND
J 1
(725 2225);
DISPLAY 0.702128 (725 2225);
PAINT GREEN (725 2225);
DISPLAY INVISIBLE (725 2225);
FORCEPROP 1 LAST PATH I22
J 0
(775 2300);
DISPLAY 0.872340 (775 2300);
PAINT AQUA (775 2300);
DISPLAY INVISIBLE (775 2300);
FORCEADD Q_CAP..2
(-450 2775);
FORCEPROP 1 LAST TOLERANCE 10%
J 2
(-450 2625);
DISPLAY 0.978723 (-450 2625);
FORCEPROP 1 LAST PACK_TYPE C0402
J 1
(-450 2575);
DISPLAY 0.978723 (-450 2575);
FORCEPROP 1 LAST PART_NUMBER CH5104KEB02
J 1
(-450 2875);
DISPLAY 0.978723 (-450 2875);
FORCEPROP 1 LAST MATERIAL X6S
J 0
(-450 2625);
DISPLAY 0.978723 (-450 2625);
FORCEPROP 1 LAST VOLTAGE 25V
J 0
(-450 2675);
DISPLAY 0.978723 (-450 2675);
FORCEPROP 1 LAST VALUE 1UF
J 2
(-450 2675);
DISPLAY 0.978723 (-450 2675);
FORCEPROP 2 LAST CDS_LIB pure_quanta
J 0
(-450 2775);
DISPLAY INVISIBLE (-450 2775);
FORCEPROP 1 LAST PATH I23
J 0
(-450 2975);
DISPLAY 0.978723 (-450 2975);
PAINT WHITE (-450 2975);
DISPLAY INVISIBLE (-450 2975);
FORCEPROP 1 LAST LOCATION C161
J 1
(-450 2925);
DISPLAY 0.978723 (-450 2925);
FORCEPROP 1 LASTPIN (-550 2775) $PN 1
J 0
(-560 2790);
DISPLAY 0.787234 (-560 2790);
PAINT MONO (-560 2790);
FORCEPROP 1 LASTPIN (-350 2775) $PN 2
J 0
(-365 2790);
DISPLAY 0.787234 (-365 2790);
PAINT MONO (-365 2790);
FORCEPROP 0 LAST $SEC 1
J 0
(-450 2975);
DISPLAY 0.680851 (-450 2975);
PAINT MONO (-450 2975);
DISPLAY INVISIBLE (-450 2975);
FORCEPROP 0 LAST CDS_SEC 1
J 0
(-450 2975);
DISPLAY 0.680851 (-450 2975);
DISPLAY INVISIBLE (-450 2975);
FORCEADD UNIVERSAL_GND..1
(325 2300);
FORCEPROP 3 LASTPIN (325 2350) SIG_NAME GND\g
J 0
(335 2360);
DISPLAY 0.659574 (335 2360);
PAINT MONO (335 2360);
DISPLAY INVISIBLE (335 2360);
FORCEPROP 1 LAST PATH I25
J 0
(400 2300);
DISPLAY 0.872340 (400 2300);
PAINT AQUA (400 2300);
DISPLAY INVISIBLE (400 2300);
FORCEPROP 1 LAST HDL_POWER GND
J 1
(350 2225);
DISPLAY 0.702128 (350 2225);
PAINT GREEN (350 2225);
DISPLAY INVISIBLE (350 2225);
FORCEPROP 2 LAST CDS_LIB logical_power
J 0
(325 2300);
DISPLAY INVISIBLE (325 2300);
FORCEADD Q_RES..2
(-175 2550);
FORCEPROP 1 LAST WATTAGE 1/16W
J 0
(-135 2525);
DISPLAY 0.978723 (-135 2525);
FORCEPROP 1 LAST MATERIAL CHIP
J 0
(-135 2475);
DISPLAY 0.978723 (-135 2475);
FORCEPROP 1 LAST PART_NUMBER CS41002FB09
J 0
(-135 2425);
DISPLAY 0.978723 (-135 2425);
FORCEPROP 1 LAST PACK_TYPE 0402LF
J 0
(-135 2375);
DISPLAY 0.978723 (-135 2375);
FORCEPROP 1 LAST VALUE 100K
J 0
(-130 2625);
DISPLAY 0.978723 (-130 2625);
FORCEPROP 1 LAST TOLERANCE 1%
J 0
(-130 2575);
DISPLAY 0.978723 (-130 2575);
FORCEPROP 1 LAST PATH I26
J 0
(-125 2725);
DISPLAY 0.978723 (-125 2725);
PAINT WHITE (-125 2725);
DISPLAY INVISIBLE (-125 2725);
FORCEPROP 2 LAST CDS_LIB pure_quanta
J 0
(-175 2550);
DISPLAY INVISIBLE (-175 2550);
FORCEPROP 1 LAST LOCATION R314
J 0
(-130 2675);
DISPLAY 0.978723 (-130 2675);
FORCEPROP 1 LASTPIN (-175 2650) $PN 1
J 0
(-170 2612);
DISPLAY 0.787234 (-170 2612);
PAINT MONO (-170 2612);
FORCEPROP 1 LASTPIN (-175 2450) $PN 2
J 0
(-170 2460);
DISPLAY 0.787234 (-170 2460);
PAINT MONO (-170 2460);
FORCEPROP 0 LAST $SEC 1
J 0
(-125 2725);
DISPLAY 0.680851 (-125 2725);
PAINT MONO (-125 2725);
DISPLAY INVISIBLE (-125 2725);
FORCEPROP 0 LAST CDS_SEC 1
J 0
(-125 2725);
DISPLAY 0.680851 (-125 2725);
DISPLAY INVISIBLE (-125 2725);
FORCEADD UNIVERSAL_GND..1
(-175 2300);
FORCEPROP 3 LASTPIN (-175 2350) SIG_NAME GND\g
J 0
(-165 2360);
DISPLAY 0.659574 (-165 2360);
PAINT MONO (-165 2360);
DISPLAY INVISIBLE (-165 2360);
FORCEPROP 1 LAST PATH I27
J 0
(-100 2300);
DISPLAY 0.872340 (-100 2300);
PAINT AQUA (-100 2300);
DISPLAY INVISIBLE (-100 2300);
FORCEPROP 1 LAST HDL_POWER GND
J 1
(-150 2225);
DISPLAY 0.702128 (-150 2225);
PAINT GREEN (-150 2225);
DISPLAY INVISIBLE (-150 2225);
FORCEPROP 2 LAST CDS_LIB logical_power
J 0
(-175 2300);
DISPLAY INVISIBLE (-175 2300);
FORCEADD Q_DIODE..1
(-1400 2775);
FORCEPROP 1 LAST PART_NUMBER BC000340033
J 0
(-1475 2905);
DISPLAY 0.723404 (-1475 2905);
PAINT GREEN (-1475 2905);
FORCEPROP 2 LAST PACK_TYPE SMLF
J 0
(-1475 3000);
DISPLAY 0.680851 (-1475 3000);
FORCEPROP 1 LAST MATERIAL IC
J 0
(-1475 2850);
DISPLAY 0.723404 (-1475 2850);
PAINT GREEN (-1475 2850);
FORCEPROP 2 LAST VALUE SDMK0340L-7-F
J 0
(-1475 3050);
DISPLAY 0.680851 (-1475 3050);
FORCEPROP 2 LAST CDS_LIB pure_quanta
J 0
(-1400 2775);
DISPLAY INVISIBLE (-1400 2775);
FORCEPROP 1 LAST NEEDS_NO_SIZE TRUE
J 0
(-1400 2775);
DISPLAY 0.468085 (-1400 2775);
PAINT GREEN (-1400 2775);
DISPLAY INVISIBLE (-1400 2775);
FORCEPROP 1 LAST PIN_NAMES_ROTATE True
J 0
(-1475 2935);
DISPLAY 0.255319 (-1475 2935);
PAINT GREEN (-1475 2935);
DISPLAY INVISIBLE (-1475 2935);
FORCEPROP 1 LAST PATH I28
J 0
(-1300 2855);
DISPLAY 0.723404 (-1300 2855);
PAINT GREEN (-1300 2855);
DISPLAY INVISIBLE (-1300 2855);
FORCEPROP 1 LAST LOCATION D17
J 0
(-1475 2960);
DISPLAY 0.723404 (-1475 2960);
PAINT GREEN (-1475 2960);
FORCEPROP 0 LASTPIN (-1525 2775) $PN 1
J 2
(-1535 2785);
DISPLAY 0.680851 (-1535 2785);
PAINT MONO (-1535 2785);
FORCEPROP 0 LASTPIN (-1275 2775) $PN 2
J 0
(-1265 2785);
DISPLAY 0.680851 (-1265 2785);
PAINT MONO (-1265 2785);
FORCEPROP 0 LAST $SEC 1
J 0
(-1475 3100);
DISPLAY 0.680851 (-1475 3100);
PAINT MONO (-1475 3100);
DISPLAY INVISIBLE (-1475 3100);
FORCEPROP 0 LAST CDS_SEC 1
J 0
(-1475 3100);
DISPLAY 0.680851 (-1475 3100);
DISPLAY INVISIBLE (-1475 3100);
FORCEADD OFFPAGE..1
(-4425 2850);
FORCEPROP 2 LAST $XR1 35 
J 0
(-4676 2814);
DISPLAY 0.638298 (-4676 2814);
PAINT MONO (-4676 2814);
FORCEPROP 2 LAST $XR0 13 
J 0
(-4676 2850);
DISPLAY 0.638298 (-4676 2850);
PAINT MONO (-4676 2850);
FORCEPROP 2 LAST PATH I29
J 0
(-4625 2900);
DISPLAY 0.680851 (-4625 2900);
DISPLAY INVISIBLE (-4625 2900);
FORCEPROP 1 LAST COMMENT_BODY TRUE
J 0
(-4295 2750);
DISPLAY 1.106383 (-4295 2750);
PAINT PEACH (-4295 2750);
DISPLAY INVISIBLE (-4295 2750);
FORCEPROP 1 LAST OFFPAGE TRUE
J 0
(-4095 2720);
PAINT GREEN (-4095 2720);
DISPLAY INVISIBLE (-4095 2720);
FORCEPROP 2 LAST CDS_LIB standard
J 0
(-4425 2850);
DISPLAY 0.808511 (-4425 2850);
PAINT MONO (-4425 2850);
DISPLAY INVISIBLE (-4425 2850);
FORCEADD UNIVERSAL_GND..1
(-575 3825);
FORCEPROP 3 LASTPIN (-575 3875) SIG_NAME GND\g
J 0
(-565 3885);
DISPLAY 0.659574 (-565 3885);
PAINT MONO (-565 3885);
DISPLAY INVISIBLE (-565 3885);
FORCEPROP 2 LAST CDS_LIB logical_power
J 0
(-575 3825);
DISPLAY INVISIBLE (-575 3825);
FORCEPROP 1 LAST HDL_POWER GND
J 1
(-550 3750);
DISPLAY 0.702128 (-550 3750);
PAINT GREEN (-550 3750);
DISPLAY INVISIBLE (-550 3750);
FORCEPROP 1 LAST PATH I3
J 0
(-500 3825);
DISPLAY 0.872340 (-500 3825);
PAINT AQUA (-500 3825);
DISPLAY INVISIBLE (-500 3825);
FORCEADD Q_RES..2
(-975 2600);
FORCEPROP 1 LAST TOLERANCE 1%
J 0
(-930 2625);
DISPLAY 0.978723 (-930 2625);
FORCEPROP 1 LAST WATTAGE 1/16W
J 0
(-935 2575);
DISPLAY 0.978723 (-935 2575);
FORCEPROP 1 LAST PART_NUMBER CS44702FB02
J 0
(-935 2475);
DISPLAY 0.978723 (-935 2475);
FORCEPROP 1 LAST MATERIAL CHIP
J 0
(-935 2525);
DISPLAY 0.978723 (-935 2525);
FORCEPROP 1 LAST PACK_TYPE 0402LF
J 0
(-935 2425);
DISPLAY 0.978723 (-935 2425);
FORCEPROP 1 LAST VALUE 470K
J 0
(-930 2675);
DISPLAY 0.978723 (-930 2675);
FORCEPROP 2 LAST CDS_LIB pure_quanta
J 0
(-975 2600);
DISPLAY INVISIBLE (-975 2600);
FORCEPROP 1 LAST PATH I30
J 0
(-925 2775);
DISPLAY 0.978723 (-925 2775);
PAINT WHITE (-925 2775);
DISPLAY INVISIBLE (-925 2775);
FORCEPROP 1 LAST LOCATION R313
J 0
(-930 2725);
DISPLAY 0.978723 (-930 2725);
FORCEPROP 1 LASTPIN (-975 2700) $PN 1
J 0
(-970 2662);
DISPLAY 0.787234 (-970 2662);
PAINT MONO (-970 2662);
FORCEPROP 1 LASTPIN (-975 2500) $PN 2
J 0
(-970 2510);
DISPLAY 0.787234 (-970 2510);
PAINT MONO (-970 2510);
FORCEPROP 0 LAST $SEC 1
J 0
(-925 2775);
DISPLAY 0.680851 (-925 2775);
PAINT MONO (-925 2775);
DISPLAY INVISIBLE (-925 2775);
FORCEPROP 0 LAST CDS_SEC 1
J 0
(-925 2775);
DISPLAY 0.680851 (-925 2775);
DISPLAY INVISIBLE (-925 2775);
FORCEADD UNIVERSAL_GND..1
(-975 2350);
FORCEPROP 3 LASTPIN (-975 2400) SIG_NAME GND\g
J 0
(-965 2410);
DISPLAY 0.659574 (-965 2410);
PAINT MONO (-965 2410);
DISPLAY INVISIBLE (-965 2410);
FORCEPROP 2 LAST CDS_LIB logical_power
J 0
(-975 2350);
DISPLAY INVISIBLE (-975 2350);
FORCEPROP 1 LAST HDL_POWER GND
J 1
(-950 2275);
DISPLAY 0.702128 (-950 2275);
PAINT GREEN (-950 2275);
DISPLAY INVISIBLE (-950 2275);
FORCEPROP 1 LAST PATH I31
J 0
(-900 2350);
DISPLAY 0.872340 (-900 2350);
PAINT AQUA (-900 2350);
DISPLAY INVISIBLE (-900 2350);
FORCEADD OFFPAGE..5
(-2875 4650);
FORCEPROP 2 LAST $XR0 46 
J 0
(-3129 4650);
DISPLAY 0.638298 (-3129 4650);
PAINT MONO (-3129 4650);
FORCEPROP 2 LAST CDS_LIB standard
J 0
(-2875 4650);
DISPLAY 0.808511 (-2875 4650);
PAINT MONO (-2875 4650);
DISPLAY INVISIBLE (-2875 4650);
FORCEPROP 1 LAST OFFPAGE TRUE
J 0
(-2550 4525);
DISPLAY 0.872340 (-2550 4525);
PAINT GREEN (-2550 4525);
DISPLAY INVISIBLE (-2550 4525);
FORCEPROP 1 LAST COMMENT_BODY TRUE
J 0
(-2775 4575);
DISPLAY 0.872340 (-2775 4575);
PAINT PEACH (-2775 4575);
DISPLAY INVISIBLE (-2775 4575);
FORCEPROP 2 LAST PATH I32
J 0
(-3075 4700);
DISPLAY 0.680851 (-3075 4700);
DISPLAY INVISIBLE (-3075 4700);
FORCEADD UNIVERSAL_GND..1
(2400 1825);
FORCEPROP 3 LASTPIN (2400 1875) SIG_NAME GND\g
J 0
(2410 1885);
DISPLAY 0.659574 (2410 1885);
PAINT MONO (2410 1885);
DISPLAY INVISIBLE (2410 1885);
FORCEPROP 2 LAST CDS_LIB logical_power
J 0
(2400 1825);
DISPLAY INVISIBLE (2400 1825);
FORCEPROP 1 LAST HDL_POWER GND
J 1
(2425 1750);
DISPLAY 0.702128 (2425 1750);
PAINT GREEN (2425 1750);
DISPLAY INVISIBLE (2425 1750);
FORCEPROP 1 LAST PATH I34
J 0
(2475 1825);
DISPLAY 0.872340 (2475 1825);
PAINT AQUA (2475 1825);
DISPLAY INVISIBLE (2475 1825);
FORCEADD Q_RES..2
(-2000 725);
FORCEPROP 1 LAST PART_NUMBER CS41002FB09
J 0
(-1960 600);
DISPLAY 0.510638 (-1960 600);
PAINT WHITE (-1960 600);
FORCEPROP 1 LAST VALUE 100K
J 0
(-1955 800);
DISPLAY 0.510638 (-1955 800);
PAINT SKYBLUE (-1955 800);
FORCEPROP 1 LAST PACK_TYPE 0402LF
J 0
(-1960 550);
DISPLAY 0.510638 (-1960 550);
PAINT SKYBLUE (-1960 550);
FORCEPROP 1 LAST MATERIAL CHIP
J 0
(-1960 650);
DISPLAY 0.510638 (-1960 650);
PAINT SKYBLUE (-1960 650);
FORCEPROP 1 LAST TOLERANCE 1%
J 0
(-1955 750);
DISPLAY 0.510638 (-1955 750);
PAINT SKYBLUE (-1955 750);
FORCEPROP 1 LAST WATTAGE 1/16W
J 0
(-1960 700);
DISPLAY 0.510638 (-1960 700);
PAINT SKYBLUE (-1960 700);
FORCEPROP 2 LAST CDS_LIB pure_quanta
J 0
(-2000 725);
DISPLAY INVISIBLE (-2000 725);
FORCEPROP 1 LAST PATH I35
J 0
(-1950 900);
DISPLAY 0.978723 (-1950 900);
PAINT WHITE (-1950 900);
DISPLAY INVISIBLE (-1950 900);
FORCEPROP 1 LAST LOCATION R614
J 0
(-1955 850);
DISPLAY 0.702128 (-1955 850);
PAINT YELLOW (-1955 850);
FORCEPROP 1 LASTPIN (-2000 825) $PN 1
J 0
(-1995 787);
DISPLAY 0.808511 (-1995 787);
PAINT WHITE (-1995 787);
FORCEPROP 1 LASTPIN (-2000 625) $PN 2
J 0
(-1995 635);
DISPLAY 0.808511 (-1995 635);
PAINT WHITE (-1995 635);
FORCEPROP 0 LAST $SEC 1
J 0
(-1950 900);
DISPLAY 0.680851 (-1950 900);
PAINT MONO (-1950 900);
DISPLAY INVISIBLE (-1950 900);
FORCEPROP 0 LAST CDS_SEC 1
J 0
(-1950 900);
DISPLAY 0.680851 (-1950 900);
DISPLAY INVISIBLE (-1950 900);
FORCEADD UNIVERSAL_GND..1
(-2000 475);
FORCEPROP 3 LASTPIN (-2000 525) SIG_NAME GND\g
J 0
(-1990 535);
DISPLAY 0.659574 (-1990 535);
PAINT MONO (-1990 535);
DISPLAY INVISIBLE (-1990 535);
FORCEPROP 2 LAST CDS_LIB logical_power
J 0
(-2000 475);
DISPLAY INVISIBLE (-2000 475);
FORCEPROP 1 LAST HDL_POWER GND
J 1
(-1975 400);
DISPLAY 0.702128 (-1975 400);
PAINT GREEN (-1975 400);
DISPLAY INVISIBLE (-1975 400);
FORCEPROP 1 LAST PATH I36
J 0
(-1925 475);
DISPLAY 0.872340 (-1925 475);
PAINT AQUA (-1925 475);
DISPLAY INVISIBLE (-1925 475);
FORCEADD MMBT39047F..1
R 2
(275 3750);
FORCEPROP 2 LAST VALUE MMBT3904-7-F
J 2
(200 3800);
DISPLAY 1.021277 (200 3800);
FORCEPROP 1 LAST PART_NUMBER BA0390400H0
J 2
(199 3710);
DISPLAY 0.723404 (199 3710);
PAINT GREEN (199 3710);
FORCEPROP 2 LAST PART_TYPE SMLF
J 2
(200 3850);
DISPLAY 1.021277 (200 3850);
FORCEPROP 1 LAST MATERIAL IC
J 2
(199 3660);
DISPLAY 0.723404 (199 3660);
PAINT GREEN (199 3660);
FORCEPROP 2 LAST SEC_TYPE 
J 0
(200 3900);
DISPLAY 1.021277 (200 3900);
DISPLAY INVISIBLE (200 3900);
FORCEPROP 1 LAST CDS_LMAN_SYM_OUTLINE -50,50,50,-50
J 2
(275 3750);
DISPLAY 0.468085 (275 3750);
PAINT GREEN (275 3750);
DISPLAY INVISIBLE (275 3750);
FORCEPROP 1 LAST NEEDS_NO_SIZE TRUE
J 2
(225 3700);
DISPLAY 0.468085 (225 3700);
PAINT GREEN (225 3700);
DISPLAY INVISIBLE (225 3700);
FORCEPROP 2 LAST CDS_LIB pure_quanta
J 2
(275 3750);
DISPLAY INVISIBLE (275 3750);
FORCEPROP 1 LAST PATH I4
J 2
(275 3750);
DISPLAY 0.723404 (275 3750);
PAINT GREEN (275 3750);
DISPLAY INVISIBLE (275 3750);
FORCEPROP 1 LAST LOCATION Q3
J 2
(206 3755);
DISPLAY 0.723404 (206 3755);
PAINT GREEN (206 3755);
FORCEPROP 0 LASTPIN (375 3750) $PN B
J 0
(385 3760);
DISPLAY 0.680851 (385 3760);
PAINT MONO (385 3760);
FORCEPROP 0 LASTPIN (225 3650) $PN E
R 1
J 2
(215 3640);
DISPLAY 0.680851 (215 3640);
PAINT MONO (215 3640);
FORCEPROP 0 LASTPIN (225 3850) $PN C
R 1
J 0
(215 3860);
DISPLAY 0.680851 (215 3860);
PAINT MONO (215 3860);
FORCEPROP 2 LAST SEC 1
J 0
(200 3900);
DISPLAY 0.680851 (200 3900);
PAINT MONO (200 3900);
DISPLAY INVISIBLE (200 3900);
FORCEADD Q_RES..1
(450 1100);
FORCEPROP 1 LAST MATERIAL CHIP
J 0
(550 1050);
DISPLAY 0.510638 (550 1050);
PAINT SKYBLUE (550 1050);
FORCEPROP 1 LAST VALUE 49.9
J 2
(350 1100);
DISPLAY 0.510638 (350 1100);
PAINT SKYBLUE (350 1100);
FORCEPROP 2 LAST CDS_LIB pure_quanta
J 0
(450 1100);
DISPLAY INVISIBLE (450 1100);
FORCEPROP 1 LAST PATH I41
J 0
(400 1250);
DISPLAY 0.978723 (400 1250);
PAINT WHITE (400 1250);
DISPLAY INVISIBLE (400 1250);
FORCEPROP 1 LAST WATTAGE 1/16W
J 2
(425 950);
DISPLAY 0.510638 (425 950);
PAINT SKYBLUE (425 950);
DISPLAY INVISIBLE (425 950);
FORCEPROP 1 LAST PACK_TYPE 0402LF
J 0
(525 1000);
DISPLAY 0.510638 (525 1000);
PAINT SKYBLUE (525 1000);
DISPLAY INVISIBLE (525 1000);
FORCEPROP 1 LAST PART_NUMBER CS04992FB07
J 0
(-75 1000);
DISPLAY 0.510638 (-75 1000);
PAINT WHITE (-75 1000);
DISPLAY INVISIBLE (-75 1000);
FORCEPROP 1 LAST TOLERANCE 1%
J 0
(450 1000);
DISPLAY 0.510638 (450 1000);
PAINT SKYBLUE (450 1000);
DISPLAY INVISIBLE (450 1000);
FORCEPROP 1 LAST LOCATION R192
J 0
(625 1100);
DISPLAY 0.702128 (625 1100);
PAINT YELLOW (625 1100);
FORCEPROP 1 LASTPIN (350 1100) $PN 1
J 0
(362 1112);
DISPLAY 0.808511 (362 1112);
PAINT WHITE (362 1112);
FORCEPROP 1 LASTPIN (550 1100) $PN 2
J 0
(512 1112);
DISPLAY 0.808511 (512 1112);
PAINT WHITE (512 1112);
FORCEPROP 0 LAST $SEC 1
J 0
(400 1200);
DISPLAY 0.680851 (400 1200);
PAINT MONO (400 1200);
DISPLAY INVISIBLE (400 1200);
FORCEPROP 0 LAST CDS_SEC 1
J 0
(575 1150);
DISPLAY 0.680851 (575 1150);
DISPLAY INVISIBLE (575 1150);
FORCEADD Q_CAP..1
(-675 1650);
FORCEPROP 1 LAST VALUE 0.1UF
J 0
(-625 1700);
DISPLAY 0.510638 (-625 1700);
PAINT SKYBLUE (-625 1700);
FORCEPROP 1 LAST VOLTAGE 25V
J 0
(-625 1650);
DISPLAY 0.510638 (-625 1650);
PAINT SKYBLUE (-625 1650);
FORCEPROP 1 LAST PART_NUMBER CH4104K1B00
J 0
(-625 1450);
DISPLAY 0.510638 (-625 1450);
PAINT WHITE (-625 1450);
FORCEPROP 1 LAST PACK_TYPE 0402
J 0
(-625 1500);
DISPLAY 0.510638 (-625 1500);
PAINT SKYBLUE (-625 1500);
FORCEPROP 1 LAST MATERIAL X7R
J 0
(-625 1550);
DISPLAY 0.510638 (-625 1550);
PAINT SKYBLUE (-625 1550);
FORCEPROP 1 LAST TOLERANCE 10%
J 0
(-625 1600);
DISPLAY 0.510638 (-625 1600);
PAINT SKYBLUE (-625 1600);
FORCEPROP 2 LAST CDS_LIB pure_quanta
J 0
(-675 1650);
DISPLAY INVISIBLE (-675 1650);
FORCEPROP 1 LAST PATH I42
J 0
(-625 1800);
DISPLAY 0.978723 (-625 1800);
PAINT WHITE (-625 1800);
DISPLAY INVISIBLE (-625 1800);
FORCEPROP 1 LAST LOCATION C34
J 0
(-625 1750);
DISPLAY 0.702128 (-625 1750);
PAINT YELLOW (-625 1750);
FORCEPROP 1 LASTPIN (-675 1750) $PN 1
J 0
(-665 1730);
DISPLAY 0.808511 (-665 1730);
PAINT WHITE (-665 1730);
FORCEPROP 1 LASTPIN (-675 1550) $PN 2
J 0
(-665 1530);
DISPLAY 0.808511 (-665 1530);
PAINT WHITE (-665 1530);
FORCEPROP 0 LAST $SEC 1
J 0
(-625 1800);
DISPLAY 0.680851 (-625 1800);
PAINT MONO (-625 1800);
DISPLAY INVISIBLE (-625 1800);
FORCEPROP 0 LAST CDS_SEC 1
J 0
(-625 1800);
DISPLAY 0.680851 (-625 1800);
DISPLAY INVISIBLE (-625 1800);
FORCEADD UNIVERSAL_GND..1
(-675 1425);
FORCEPROP 3 LASTPIN (-675 1475) SIG_NAME GND\g
J 0
(-665 1485);
DISPLAY 0.659574 (-665 1485);
PAINT MONO (-665 1485);
DISPLAY INVISIBLE (-665 1485);
FORCEPROP 2 LAST CDS_LIB logical_power
J 0
(-675 1425);
DISPLAY INVISIBLE (-675 1425);
FORCEPROP 1 LAST HDL_POWER GND
J 1
(-650 1350);
DISPLAY 0.702128 (-650 1350);
PAINT GREEN (-650 1350);
DISPLAY INVISIBLE (-650 1350);
FORCEPROP 1 LAST PATH I43
J 0
(-600 1425);
DISPLAY 0.872340 (-600 1425);
PAINT AQUA (-600 1425);
DISPLAY INVISIBLE (-600 1425);
FORCEADD UNIVERSAL_POWER..1
(-875 1925);
FORCEPROP 3 LASTPIN (-875 1875) SIG_NAME P3V3_AUX\g
J 0
(-865 1885);
DISPLAY 0.659574 (-865 1885);
PAINT MONO (-865 1885);
DISPLAY INVISIBLE (-865 1885);
FORCEPROP 1 LAST HDL_POWER P3V3_AUX
J 1
(-875 1975);
DISPLAY 0.702128 (-875 1975);
PAINT GREEN (-875 1975);
FORCEPROP 2 LAST CDS_LIB logical_power
J 0
(-875 1925);
DISPLAY INVISIBLE (-875 1925);
FORCEPROP 1 LAST PATH I44
J 0
(-825 1950);
DISPLAY 0.872340 (-825 1950);
PAINT AQUA (-825 1950);
DISPLAY INVISIBLE (-825 1950);
FORCEADD UNIVERSAL_GND..1
(1275 575);
FORCEPROP 3 LASTPIN (1275 625) SIG_NAME GND\g
J 0
(1285 635);
DISPLAY 0.659574 (1285 635);
PAINT MONO (1285 635);
DISPLAY INVISIBLE (1285 635);
FORCEPROP 1 LAST PATH I45
J 0
(1350 575);
DISPLAY 0.872340 (1350 575);
PAINT AQUA (1350 575);
DISPLAY INVISIBLE (1350 575);
FORCEPROP 1 LAST HDL_POWER GND
J 1
(1300 500);
DISPLAY 0.702128 (1300 500);
PAINT GREEN (1300 500);
DISPLAY INVISIBLE (1300 500);
FORCEPROP 2 LAST CDS_LIB logical_power
J 0
(1275 575);
DISPLAY INVISIBLE (1275 575);
FORCEADD Q_CAP..1
(1275 775);
FORCEPROP 1 LAST VALUE 4700P
J 0
(1325 825);
DISPLAY 0.510638 (1325 825);
PAINT SKYBLUE (1325 825);
FORCEPROP 1 LAST PART_NUMBER CH2474K1B08
J 0
(1325 625);
DISPLAY 0.510638 (1325 625);
PAINT WHITE (1325 625);
FORCEPROP 1 LAST MATERIAL EMPTY
J 0
(1325 675);
DISPLAY 0.510638 (1325 675);
PAINT RED (1325 675);
FORCEPROP 1 LAST TOLERANCE 10%
J 0
(1325 725);
DISPLAY 0.510638 (1325 725);
PAINT SKYBLUE (1325 725);
FORCEPROP 1 LAST VOLTAGE 25V
J 0
(1325 775);
DISPLAY 0.510638 (1325 775);
PAINT SKYBLUE (1325 775);
FORCEPROP 1 LAST PACK_TYPE C0402
J 0
(1325 575);
DISPLAY 0.510638 (1325 575);
PAINT SKYBLUE (1325 575);
FORCEPROP 1 LAST PATH I46
J 0
(1325 925);
DISPLAY 0.978723 (1325 925);
PAINT WHITE (1325 925);
DISPLAY INVISIBLE (1325 925);
FORCEPROP 2 LAST CDS_LIB pure_quanta
J 0
(1275 775);
DISPLAY INVISIBLE (1275 775);
FORCEPROP 1 LAST LOCATION C223
J 0
(1325 875);
DISPLAY 0.702128 (1325 875);
PAINT YELLOW (1325 875);
FORCEPROP 0 LAST $SEC 1
J 0
(1325 925);
DISPLAY 0.680851 (1325 925);
PAINT MONO (1325 925);
DISPLAY INVISIBLE (1325 925);
FORCEPROP 0 LAST CDS_SEC 1
J 0
(1325 925);
DISPLAY 1.021277 (1325 925);
DISPLAY INVISIBLE (1325 925);
FORCEPROP 1 LASTPIN (1275 875) $PN 1
J 0
(1285 855);
DISPLAY 0.808511 (1285 855);
PAINT WHITE (1285 855);
DISPLAY INVISIBLE (1285 855);
FORCEPROP 1 LASTPIN (1275 675) $PN 2
J 0
(1285 655);
DISPLAY 0.808511 (1285 655);
PAINT WHITE (1285 655);
DISPLAY INVISIBLE (1285 655);
FORCEADD UNIVERSAL_GND..1
(-1725 750);
FORCEPROP 3 LASTPIN (-1725 800) SIG_NAME GND\g
J 0
(-1715 810);
DISPLAY 0.659574 (-1715 810);
PAINT MONO (-1715 810);
DISPLAY INVISIBLE (-1715 810);
FORCEPROP 2 LAST CDS_LIB logical_power
J 0
(-1725 750);
DISPLAY INVISIBLE (-1725 750);
FORCEPROP 1 LAST HDL_POWER GND
J 1
(-1700 675);
DISPLAY 0.702128 (-1700 675);
PAINT GREEN (-1700 675);
DISPLAY INVISIBLE (-1700 675);
FORCEPROP 1 LAST PATH I48
J 0
(-1650 750);
DISPLAY 0.872340 (-1650 750);
PAINT AQUA (-1650 750);
DISPLAY INVISIBLE (-1650 750);
FORCEADD Q_RES..1
(-2425 1800);
FORCEPROP 1 LAST TOLERANCE 5%
J 0
(-2675 1750);
DISPLAY 0.510638 (-2675 1750);
PAINT SKYBLUE (-2675 1750);
FORCEPROP 1 LAST WATTAGE 1/16W
J 2
(-2175 1750);
DISPLAY 0.510638 (-2175 1750);
PAINT SKYBLUE (-2175 1750);
FORCEPROP 1 LAST VALUE 0
J 2
(-2200 1800);
DISPLAY 0.510638 (-2200 1800);
PAINT SKYBLUE (-2200 1800);
FORCEPROP 1 LAST PACK_TYPE 0402LF
J 0
(-2125 1750);
DISPLAY 0.510638 (-2125 1750);
PAINT SKYBLUE (-2125 1750);
FORCEPROP 1 LAST MATERIAL EMPTY
J 0
(-2575 1725);
DISPLAY 0.510638 (-2575 1725);
PAINT RED (-2575 1725);
FORCEPROP 2 LAST CDS_LIB pure_quanta
J 0
(-2425 1800);
DISPLAY INVISIBLE (-2425 1800);
FORCEPROP 1 LAST PATH I49
J 0
(-2475 1950);
DISPLAY 0.978723 (-2475 1950);
PAINT WHITE (-2475 1950);
DISPLAY INVISIBLE (-2475 1950);
FORCEPROP 1 LAST PART_NUMBER CS00002JB13
J 0
(-2525 1850);
DISPLAY 0.510638 (-2525 1850);
PAINT WHITE (-2525 1850);
DISPLAY INVISIBLE (-2525 1850);
FORCEPROP 1 LAST LOCATION R711
J 0
(-2675 1800);
DISPLAY 0.702128 (-2675 1800);
PAINT YELLOW (-2675 1800);
FORCEPROP 1 LASTPIN (-2525 1800) $PN 1
J 0
(-2513 1812);
DISPLAY 0.808511 (-2513 1812);
PAINT WHITE (-2513 1812);
FORCEPROP 1 LASTPIN (-2325 1800) $PN 2
J 0
(-2363 1812);
DISPLAY 0.808511 (-2363 1812);
PAINT WHITE (-2363 1812);
FORCEPROP 2 LAST $SEC 1
J 0
(-2550 2025);
DISPLAY 0.680851 (-2550 2025);
PAINT MONO (-2550 2025);
DISPLAY INVISIBLE (-2550 2025);
FORCEPROP 0 LAST CDS_SEC 1
J 0
(-2550 2025);
DISPLAY 0.680851 (-2550 2025);
PAINT MONO (-2550 2025);
DISPLAY INVISIBLE (-2550 2025);
FORCEADD Q_RES..2
(-575 4400);
FORCEPROP 1 LAST VALUE 499
J 0
(-530 4475);
DISPLAY 0.978723 (-530 4475);
FORCEPROP 1 LAST TOLERANCE 1%
J 0
(-530 4425);
DISPLAY 0.978723 (-530 4425);
FORCEPROP 1 LAST WATTAGE 1/16W
J 0
(-535 4375);
DISPLAY 0.978723 (-535 4375);
FORCEPROP 1 LAST MATERIAL CHIP
J 0
(-535 4325);
DISPLAY 0.978723 (-535 4325);
FORCEPROP 1 LAST PACK_TYPE 0402LF
J 0
(-535 4225);
DISPLAY 0.978723 (-535 4225);
FORCEPROP 1 LAST PART_NUMBER CS14992FB06
J 0
(-535 4275);
DISPLAY 0.978723 (-535 4275);
FORCEPROP 2 LAST CDS_LIB pure_quanta
J 0
(-575 4400);
DISPLAY INVISIBLE (-575 4400);
FORCEPROP 1 LAST PATH I5
J 0
(-525 4575);
DISPLAY 0.978723 (-525 4575);
PAINT WHITE (-525 4575);
DISPLAY INVISIBLE (-525 4575);
FORCEPROP 1 LAST LOCATION R287
J 0
(-530 4525);
DISPLAY 0.978723 (-530 4525);
FORCEPROP 1 LASTPIN (-575 4500) $PN 1
J 0
(-570 4462);
DISPLAY 0.787234 (-570 4462);
PAINT MONO (-570 4462);
FORCEPROP 1 LASTPIN (-575 4300) $PN 2
J 0
(-570 4310);
DISPLAY 0.787234 (-570 4310);
PAINT MONO (-570 4310);
FORCEPROP 0 LAST $SEC 1
J 0
(-525 4575);
DISPLAY 0.680851 (-525 4575);
PAINT MONO (-525 4575);
DISPLAY INVISIBLE (-525 4575);
FORCEPROP 0 LAST CDS_SEC 1
J 0
(-525 4575);
DISPLAY 0.680851 (-525 4575);
DISPLAY INVISIBLE (-525 4575);
FORCEADD OFFPAGE..1
(-3525 1425);
FORCEPROP 2 LAST $XR0 22 
J 0
(-3746 1425);
DISPLAY 0.638298 (-3746 1425);
PAINT MONO (-3746 1425);
FORCEPROP 1 LAST COMMENT_BODY TRUE
J 0
(-3400 1325);
DISPLAY 0.872340 (-3400 1325);
PAINT PEACH (-3400 1325);
DISPLAY INVISIBLE (-3400 1325);
FORCEPROP 1 LAST OFFPAGE TRUE
J 0
(-3200 1300);
DISPLAY 0.872340 (-3200 1300);
PAINT GREEN (-3200 1300);
DISPLAY INVISIBLE (-3200 1300);
FORCEPROP 2 LAST CDS_LIB standard
J 0
(-3525 1425);
DISPLAY INVISIBLE (-3525 1425);
FORCEPROP 2 LAST PATH I50
J 0
(-3775 1475);
DISPLAY 0.680851 (-3775 1475);
DISPLAY INVISIBLE (-3775 1475);
FORCEADD OFFPAGE..1
(-3525 1800);
FORCEPROP 2 LAST $XR1 11 
J 0
(-3836 1800);
DISPLAY 0.638298 (-3836 1800);
PAINT MONO (-3836 1800);
FORCEPROP 2 LAST $XR4 34 
J 0
(-4106 1800);
DISPLAY 0.638298 (-4106 1800);
PAINT MONO (-4106 1800);
FORCEPROP 2 LAST $XR2 13 
J 0
(-3926 1800);
DISPLAY 0.638298 (-3926 1800);
PAINT MONO (-3926 1800);
FORCEPROP 2 LAST $XR3 28 
J 0
(-4016 1800);
DISPLAY 0.638298 (-4016 1800);
PAINT MONO (-4016 1800);
FORCEPROP 2 LAST $XR0 10 
J 0
(-3746 1800);
DISPLAY 0.638298 (-3746 1800);
PAINT MONO (-3746 1800);
FORCEPROP 2 LAST CDS_LIB standard
J 0
(-3525 1800);
DISPLAY INVISIBLE (-3525 1800);
FORCEPROP 1 LAST OFFPAGE TRUE
J 0
(-3200 1675);
DISPLAY 0.872340 (-3200 1675);
PAINT GREEN (-3200 1675);
DISPLAY INVISIBLE (-3200 1675);
FORCEPROP 1 LAST COMMENT_BODY TRUE
J 0
(-3400 1700);
DISPLAY 0.872340 (-3400 1700);
PAINT PEACH (-3400 1700);
DISPLAY INVISIBLE (-3400 1700);
FORCEPROP 2 LAST PATH I52
J 0
(-3775 1850);
DISPLAY 0.680851 (-3775 1850);
DISPLAY INVISIBLE (-3775 1850);
FORCEADD VCCAUX15..1
(-400 675);
FORCEPROP 3 LASTPIN (-400 625) SIG_NAME P1V0_AUX\g
J 0
(-390 635);
DISPLAY 0.659574 (-390 635);
PAINT MONO (-390 635);
DISPLAY INVISIBLE (-390 635);
FORCEPROP 1 LAST HDL_POWER P1V0_AUX
J 1
(-400 725);
DISPLAY 0.702128 (-400 725);
PAINT GREEN (-400 725);
FORCEPROP 2 LAST CDS_LIB logical_power
J 0
(-400 675);
DISPLAY INVISIBLE (-400 675);
FORCEPROP 1 LAST PATH I53
J 0
(-350 700);
DISPLAY 0.872340 (-350 700);
PAINT AQUA (-350 700);
DISPLAY INVISIBLE (-350 700);
FORCEADD UNIVERSAL_POWER..1
(-250 425);
FORCEPROP 3 LASTPIN (-250 375) SIG_NAME P3V3_AUX\g
J 0
(-240 385);
DISPLAY 0.659574 (-240 385);
PAINT MONO (-240 385);
DISPLAY INVISIBLE (-240 385);
FORCEPROP 1 LAST HDL_POWER P3V3_AUX
J 1
(-250 475);
DISPLAY 0.702128 (-250 475);
PAINT GREEN (-250 475);
FORCEPROP 2 LAST CDS_LIB logical_power
J 0
(-250 425);
DISPLAY INVISIBLE (-250 425);
FORCEPROP 1 LAST PATH I54
J 0
(-200 450);
DISPLAY 0.872340 (-200 450);
PAINT AQUA (-200 450);
DISPLAY INVISIBLE (-200 450);
FORCEADD Q_RES..2
(-250 0);
FORCEPROP 1 LAST PART_NUMBER CS41002FB09
J 0
(-210 -125);
DISPLAY 0.510638 (-210 -125);
PAINT WHITE (-210 -125);
FORCEPROP 1 LAST PACK_TYPE 0402LF
J 0
(-210 -175);
DISPLAY 0.510638 (-210 -175);
PAINT SKYBLUE (-210 -175);
FORCEPROP 1 LAST VALUE 100K
J 0
(-205 75);
DISPLAY 0.510638 (-205 75);
PAINT SKYBLUE (-205 75);
FORCEPROP 1 LAST MATERIAL CHIP
J 0
(-210 -75);
DISPLAY 0.510638 (-210 -75);
PAINT SKYBLUE (-210 -75);
FORCEPROP 1 LAST WATTAGE 1/16W
J 0
(-210 -25);
DISPLAY 0.510638 (-210 -25);
PAINT SKYBLUE (-210 -25);
FORCEPROP 1 LAST TOLERANCE 1%
J 0
(-205 25);
DISPLAY 0.510638 (-205 25);
PAINT SKYBLUE (-205 25);
FORCEPROP 1 LAST PATH I55
J 0
(-200 175);
DISPLAY 0.978723 (-200 175);
PAINT WHITE (-200 175);
DISPLAY INVISIBLE (-200 175);
FORCEPROP 2 LAST CDS_LIB pure_quanta
J 0
(-250 0);
DISPLAY INVISIBLE (-250 0);
FORCEPROP 1 LAST LOCATION R710
J 0
(-205 125);
DISPLAY 0.702128 (-205 125);
PAINT YELLOW (-205 125);
FORCEPROP 1 LASTPIN (-250 100) $PN 1
J 0
(-245 62);
DISPLAY 0.808511 (-245 62);
PAINT WHITE (-245 62);
FORCEPROP 1 LASTPIN (-250 -100) $PN 2
J 0
(-245 -90);
DISPLAY 0.808511 (-245 -90);
PAINT WHITE (-245 -90);
FORCEPROP 0 LAST $SEC 1
J 0
(-200 175);
DISPLAY 0.680851 (-200 175);
PAINT MONO (-200 175);
DISPLAY INVISIBLE (-200 175);
FORCEPROP 0 LAST CDS_SEC 1
J 0
(-200 175);
DISPLAY 0.680851 (-200 175);
DISPLAY INVISIBLE (-200 175);
FORCEADD UNIVERSAL_POWER..1
(-550 475);
FORCEPROP 3 LASTPIN (-550 425) SIG_NAME P3V3_AUX\g
J 0
(-540 435);
DISPLAY 0.659574 (-540 435);
PAINT MONO (-540 435);
DISPLAY INVISIBLE (-540 435);
FORCEPROP 1 LAST HDL_POWER P3V3_AUX
J 1
(-550 525);
DISPLAY 0.702128 (-550 525);
PAINT GREEN (-550 525);
FORCEPROP 2 LAST CDS_LIB logical_power
J 0
(-550 475);
DISPLAY INVISIBLE (-550 475);
FORCEPROP 1 LAST PATH I56
J 0
(-500 500);
DISPLAY 0.872340 (-500 500);
PAINT AQUA (-500 500);
DISPLAY INVISIBLE (-500 500);
FORCEADD Q_CAP..1
(-875 225);
FORCEPROP 1 LAST VOLTAGE 25V
J 0
(-825 225);
DISPLAY 0.510638 (-825 225);
PAINT SKYBLUE (-825 225);
FORCEPROP 1 LAST VALUE 0.1UF
J 0
(-825 275);
DISPLAY 0.510638 (-825 275);
PAINT SKYBLUE (-825 275);
FORCEPROP 1 LAST TOLERANCE 10%
J 0
(-825 175);
DISPLAY 0.510638 (-825 175);
PAINT SKYBLUE (-825 175);
FORCEPROP 1 LAST MATERIAL X7R
J 0
(-825 125);
DISPLAY 0.510638 (-825 125);
PAINT SKYBLUE (-825 125);
FORCEPROP 1 LAST PACK_TYPE 0402
J 0
(-825 75);
DISPLAY 0.510638 (-825 75);
PAINT SKYBLUE (-825 75);
FORCEPROP 1 LAST PART_NUMBER CH4104K1B00
J 0
(-825 25);
DISPLAY 0.510638 (-825 25);
PAINT WHITE (-825 25);
FORCEPROP 2 LAST CDS_LIB pure_quanta
J 0
(-875 225);
DISPLAY INVISIBLE (-875 225);
FORCEPROP 1 LAST PATH I57
J 0
(-825 375);
DISPLAY 0.978723 (-825 375);
PAINT WHITE (-825 375);
DISPLAY INVISIBLE (-825 375);
FORCEPROP 1 LAST LOCATION C253
J 0
(-825 325);
DISPLAY 0.702128 (-825 325);
PAINT YELLOW (-825 325);
FORCEPROP 1 LASTPIN (-875 325) $PN 1
J 0
(-865 305);
DISPLAY 0.808511 (-865 305);
PAINT WHITE (-865 305);
FORCEPROP 1 LASTPIN (-875 125) $PN 2
J 0
(-865 105);
DISPLAY 0.808511 (-865 105);
PAINT WHITE (-865 105);
FORCEPROP 0 LAST $SEC 1
J 0
(-825 375);
DISPLAY 0.680851 (-825 375);
PAINT MONO (-825 375);
DISPLAY INVISIBLE (-825 375);
FORCEPROP 0 LAST CDS_SEC 1
J 0
(-825 375);
DISPLAY 0.680851 (-825 375);
DISPLAY INVISIBLE (-825 375);
FORCEADD UNIVERSAL_GND..1
(-875 0);
FORCEPROP 3 LASTPIN (-875 50) SIG_NAME GND\g
J 0
(-865 60);
DISPLAY 0.659574 (-865 60);
PAINT MONO (-865 60);
DISPLAY INVISIBLE (-865 60);
FORCEPROP 2 LAST CDS_LIB logical_power
J 0
(-875 0);
DISPLAY INVISIBLE (-875 0);
FORCEPROP 1 LAST HDL_POWER GND
J 1
(-850 -75);
DISPLAY 0.702128 (-850 -75);
PAINT GREEN (-850 -75);
DISPLAY INVISIBLE (-850 -75);
FORCEPROP 1 LAST PATH I58
J 0
(-800 0);
DISPLAY 0.872340 (-800 0);
PAINT AQUA (-800 0);
DISPLAY INVISIBLE (-800 0);
FORCEADD Q_CAP..1
(-250 -425);
FORCEPROP 1 LAST PART_NUMBER CH4104K1B00
J 0
(-200 -625);
DISPLAY 0.510638 (-200 -625);
PAINT WHITE (-200 -625);
FORCEPROP 1 LAST VALUE 0.1UF
J 0
(-200 -375);
DISPLAY 0.510638 (-200 -375);
PAINT SKYBLUE (-200 -375);
FORCEPROP 1 LAST TOLERANCE 10%
J 0
(-200 -475);
DISPLAY 0.510638 (-200 -475);
PAINT SKYBLUE (-200 -475);
FORCEPROP 1 LAST MATERIAL X7R
J 0
(-200 -525);
DISPLAY 0.510638 (-200 -525);
PAINT SKYBLUE (-200 -525);
FORCEPROP 1 LAST PACK_TYPE 0402
J 0
(-200 -575);
DISPLAY 0.510638 (-200 -575);
PAINT SKYBLUE (-200 -575);
FORCEPROP 1 LAST VOLTAGE 25V
J 0
(-200 -425);
DISPLAY 0.510638 (-200 -425);
PAINT SKYBLUE (-200 -425);
FORCEPROP 1 LAST PATH I59
J 0
(-200 -275);
DISPLAY 0.978723 (-200 -275);
PAINT WHITE (-200 -275);
DISPLAY INVISIBLE (-200 -275);
FORCEPROP 2 LAST CDS_LIB pure_quanta
J 0
(-250 -425);
DISPLAY INVISIBLE (-250 -425);
FORCEPROP 1 LAST LOCATION C264
J 0
(-200 -325);
DISPLAY 0.702128 (-200 -325);
PAINT YELLOW (-200 -325);
FORCEPROP 1 LASTPIN (-250 -325) $PN 1
J 0
(-240 -345);
DISPLAY 0.808511 (-240 -345);
PAINT WHITE (-240 -345);
FORCEPROP 1 LASTPIN (-250 -525) $PN 2
J 0
(-240 -545);
DISPLAY 0.808511 (-240 -545);
PAINT WHITE (-240 -545);
FORCEPROP 0 LAST $SEC 1
J 0
(-200 -275);
DISPLAY 0.680851 (-200 -275);
PAINT MONO (-200 -275);
DISPLAY INVISIBLE (-200 -275);
FORCEPROP 0 LAST CDS_SEC 1
J 0
(-200 -275);
DISPLAY 0.680851 (-200 -275);
DISPLAY INVISIBLE (-200 -275);
FORCEADD UNIVERSAL_GND..1
(225 3350);
FORCEPROP 3 LASTPIN (225 3400) SIG_NAME GND\g
J 0
(235 3410);
DISPLAY 0.659574 (235 3410);
PAINT MONO (235 3410);
DISPLAY INVISIBLE (235 3410);
FORCEPROP 2 LAST CDS_LIB logical_power
J 0
(225 3350);
DISPLAY INVISIBLE (225 3350);
FORCEPROP 1 LAST HDL_POWER GND
J 1
(250 3275);
DISPLAY 0.702128 (250 3275);
PAINT GREEN (250 3275);
DISPLAY INVISIBLE (250 3275);
FORCEPROP 1 LAST PATH I6
J 0
(300 3350);
DISPLAY 0.872340 (300 3350);
PAINT AQUA (300 3350);
DISPLAY INVISIBLE (300 3350);
FORCEADD UNIVERSAL_GND..1
(-1550 -725);
FORCEPROP 3 LASTPIN (-1550 -675) SIG_NAME GND\g
J 0
(-1540 -665);
DISPLAY 0.659574 (-1540 -665);
PAINT MONO (-1540 -665);
DISPLAY INVISIBLE (-1540 -665);
FORCEPROP 1 LAST HDL_POWER GND
J 1
(-1525 -800);
DISPLAY 0.702128 (-1525 -800);
PAINT GREEN (-1525 -800);
DISPLAY INVISIBLE (-1525 -800);
FORCEPROP 1 LAST PATH I61
J 0
(-1475 -725);
DISPLAY 0.872340 (-1475 -725);
PAINT AQUA (-1475 -725);
DISPLAY INVISIBLE (-1475 -725);
FORCEPROP 2 LAST CDS_LIB logical_power
J 0
(-1550 -725);
DISPLAY INVISIBLE (-1550 -725);
FORCEADD Q_RES..1
(450 1000);
FORCEPROP 1 LAST PACK_TYPE 0402LF
J 0
(400 900);
DISPLAY 0.510638 (400 900);
PAINT SKYBLUE (400 900);
FORCEPROP 1 LAST MATERIAL CHIP
J 0
(550 900);
DISPLAY 0.510638 (550 900);
PAINT SKYBLUE (550 900);
FORCEPROP 1 LAST TOLERANCE 1%
J 0
(600 950);
DISPLAY 0.510638 (600 950);
PAINT SKYBLUE (600 950);
FORCEPROP 1 LAST PART_NUMBER CS04992FB07
J 0
(100 950);
DISPLAY 0.510638 (100 950);
PAINT WHITE (100 950);
FORCEPROP 1 LAST WATTAGE 1/16W
J 2
(325 900);
DISPLAY 0.510638 (325 900);
PAINT SKYBLUE (325 900);
FORCEPROP 1 LAST VALUE 49.9
J 2
(350 1000);
DISPLAY 0.510638 (350 1000);
PAINT SKYBLUE (350 1000);
FORCEPROP 2 LAST CDS_LIB pure_quanta
J 0
(450 1000);
DISPLAY INVISIBLE (450 1000);
FORCEPROP 1 LAST PATH I65
J 0
(400 1150);
DISPLAY 0.978723 (400 1150);
PAINT WHITE (400 1150);
DISPLAY INVISIBLE (400 1150);
FORCEPROP 1 LAST LOCATION R108
J 0
(625 1000);
DISPLAY 0.702128 (625 1000);
PAINT YELLOW (625 1000);
FORCEPROP 1 LASTPIN (350 1000) $PN 1
J 0
(362 1012);
DISPLAY 0.808511 (362 1012);
PAINT WHITE (362 1012);
FORCEPROP 1 LASTPIN (550 1000) $PN 2
J 0
(512 1012);
DISPLAY 0.808511 (512 1012);
PAINT WHITE (512 1012);
FORCEPROP 0 LAST $SEC 1
J 0
(400 1100);
DISPLAY 0.680851 (400 1100);
PAINT MONO (400 1100);
DISPLAY INVISIBLE (400 1100);
FORCEPROP 0 LAST CDS_SEC 1
J 0
(575 1050);
DISPLAY 0.680851 (575 1050);
DISPLAY INVISIBLE (575 1050);
FORCEADD UNIVERSAL_POWER..1
(1275 2850);
FORCEPROP 3 LASTPIN (1275 2800) SIG_NAME P3V3_AUX\g
J 0
(1285 2810);
DISPLAY 0.659574 (1285 2810);
PAINT MONO (1285 2810);
DISPLAY INVISIBLE (1285 2810);
FORCEPROP 1 LAST HDL_POWER P3V3_AUX
J 1
(1275 2900);
DISPLAY 0.702128 (1275 2900);
PAINT GREEN (1275 2900);
FORCEPROP 2 LAST CDS_LIB logical_power
J 0
(1275 2850);
DISPLAY INVISIBLE (1275 2850);
FORCEPROP 1 LAST PATH I66
J 0
(1325 2875);
DISPLAY 0.872340 (1325 2875);
PAINT AQUA (1325 2875);
DISPLAY INVISIBLE (1325 2875);
FORCEADD Q_RES..2
(1275 2525);
FORCEPROP 1 LAST PACK_TYPE 0402LF
J 0
(1315 2350);
DISPLAY 0.978723 (1315 2350);
FORCEPROP 1 LAST PART_NUMBER CS22002FB07
J 0
(1315 2400);
DISPLAY 0.978723 (1315 2400);
FORCEPROP 1 LAST WATTAGE 1/16W
J 0
(1315 2500);
DISPLAY 0.978723 (1315 2500);
FORCEPROP 1 LAST TOLERANCE 1%
J 0
(1320 2550);
DISPLAY 0.978723 (1320 2550);
FORCEPROP 1 LAST MATERIAL CHIP
J 0
(1315 2450);
DISPLAY 0.978723 (1315 2450);
FORCEPROP 1 LAST VALUE 2K
J 0
(1320 2600);
DISPLAY 0.978723 (1320 2600);
FORCEPROP 2 LAST CDS_LIB pure_quanta
J 0
(1275 2525);
DISPLAY INVISIBLE (1275 2525);
FORCEPROP 1 LAST PATH I67
J 0
(1325 2700);
DISPLAY 0.978723 (1325 2700);
PAINT WHITE (1325 2700);
DISPLAY INVISIBLE (1325 2700);
FORCEPROP 1 LAST LOCATION R124
J 0
(1320 2650);
DISPLAY 0.978723 (1320 2650);
FORCEPROP 1 LASTPIN (1275 2625) $PN 1
J 0
(1280 2587);
DISPLAY 0.787234 (1280 2587);
PAINT MONO (1280 2587);
FORCEPROP 1 LASTPIN (1275 2425) $PN 2
J 0
(1280 2435);
DISPLAY 0.787234 (1280 2435);
PAINT MONO (1280 2435);
FORCEPROP 0 LAST $SEC 1
J 0
(1325 2700);
DISPLAY 0.680851 (1325 2700);
PAINT MONO (1325 2700);
DISPLAY INVISIBLE (1325 2700);
FORCEPROP 0 LAST CDS_SEC 1
J 0
(1325 2700);
DISPLAY 0.680851 (1325 2700);
DISPLAY INVISIBLE (1325 2700);
FORCEADD OFFPAGE..2
(4100 1425);
FORCEPROP 2 LAST $XR1 22 
J 0
(4379 1425);
DISPLAY 0.638298 (4379 1425);
PAINT MONO (4379 1425);
FORCEPROP 2 LAST $XR0 15 
J 0
(4289 1425);
DISPLAY 0.638298 (4289 1425);
PAINT MONO (4289 1425);
FORCEPROP 2 LAST CDS_LIB standard
J 0
(4100 1425);
DISPLAY INVISIBLE (4100 1425);
FORCEPROP 1 LAST OFFPAGE TRUE
J 0
(4425 1300);
DISPLAY 0.872340 (4425 1300);
PAINT GREEN (4425 1300);
DISPLAY INVISIBLE (4425 1300);
FORCEPROP 1 LAST COMMENT_BODY TRUE
J 0
(4055 1330);
DISPLAY 0.872340 (4055 1330);
PAINT PEACH (4055 1330);
DISPLAY INVISIBLE (4055 1330);
FORCEPROP 2 LAST PATH I68
J 0
(4300 1475);
DISPLAY 0.680851 (4300 1475);
DISPLAY INVISIBLE (4300 1475);
FORCEADD Q_RES..1
(3075 1425);
FORCEPROP 1 LAST PART_NUMBER CS11002FB07
J 0
(2825 1375);
DISPLAY 0.510638 (2825 1375);
PAINT WHITE (2825 1375);
FORCEPROP 1 LAST MATERIAL CHIP
J 0
(2750 1325);
DISPLAY 0.510638 (2750 1325);
PAINT SKYBLUE (2750 1325);
FORCEPROP 1 LAST PACK_TYPE 0402LF
J 0
(2900 1325);
DISPLAY 0.510638 (2900 1325);
PAINT SKYBLUE (2900 1325);
FORCEPROP 1 LAST WATTAGE 1/16W
J 2
(2725 1325);
DISPLAY 0.510638 (2725 1325);
PAINT SKYBLUE (2725 1325);
FORCEPROP 1 LAST TOLERANCE 1%
J 0
(3100 1325);
DISPLAY 0.510638 (3100 1325);
PAINT SKYBLUE (3100 1325);
FORCEPROP 1 LAST VALUE 100
J 0
(3175 1425);
DISPLAY 0.510638 (3175 1425);
PAINT SKYBLUE (3175 1425);
FORCEPROP 1 LAST PATH I69
J 0
(3025 1575);
DISPLAY 0.978723 (3025 1575);
PAINT WHITE (3025 1575);
DISPLAY INVISIBLE (3025 1575);
FORCEPROP 2 LAST CDS_LIB pure_quanta
J 0
(3075 1425);
DISPLAY INVISIBLE (3075 1425);
FORCEPROP 1 LAST LOCATION R125
J 0
(2875 1425);
DISPLAY 0.702128 (2875 1425);
PAINT YELLOW (2875 1425);
FORCEPROP 1 LASTPIN (2975 1425) $PN 1
J 0
(2987 1437);
DISPLAY 0.808511 (2987 1437);
PAINT WHITE (2987 1437);
FORCEPROP 1 LASTPIN (3175 1425) $PN 2
J 0
(3137 1437);
DISPLAY 0.808511 (3137 1437);
PAINT WHITE (3137 1437);
FORCEPROP 0 LAST $SEC 1
J 0
(3200 1475);
DISPLAY 0.680851 (3200 1475);
PAINT MONO (3200 1475);
DISPLAY INVISIBLE (3200 1475);
FORCEPROP 0 LAST CDS_SEC 1
J 0
(3200 1475);
DISPLAY 0.680851 (3200 1475);
DISPLAY INVISIBLE (3200 1475);
FORCEADD Q_RES..2
(225 4400);
FORCEPROP 1 LAST PACK_TYPE 0402LF
J 0
(265 4225);
DISPLAY 0.978723 (265 4225);
FORCEPROP 1 LAST PART_NUMBER CS31002FB08
J 0
(265 4275);
DISPLAY 0.978723 (265 4275);
FORCEPROP 1 LAST TOLERANCE 1%
J 0
(270 4425);
DISPLAY 0.978723 (270 4425);
FORCEPROP 1 LAST WATTAGE 1/16W
J 0
(265 4375);
DISPLAY 0.978723 (265 4375);
FORCEPROP 1 LAST MATERIAL CHIP
J 0
(265 4325);
DISPLAY 0.978723 (265 4325);
FORCEPROP 1 LAST VALUE 10K
J 0
(270 4475);
DISPLAY 0.978723 (270 4475);
FORCEPROP 2 LAST CDS_LIB pure_quanta
J 0
(225 4400);
DISPLAY INVISIBLE (225 4400);
FORCEPROP 1 LAST PATH I7
J 0
(275 4575);
DISPLAY 0.978723 (275 4575);
PAINT WHITE (275 4575);
DISPLAY INVISIBLE (275 4575);
FORCEPROP 1 LAST LOCATION R289
J 0
(270 4525);
DISPLAY 0.978723 (270 4525);
FORCEPROP 1 LASTPIN (225 4500) $PN 1
J 0
(230 4462);
DISPLAY 0.787234 (230 4462);
PAINT MONO (230 4462);
FORCEPROP 1 LASTPIN (225 4300) $PN 2
J 0
(230 4310);
DISPLAY 0.787234 (230 4310);
PAINT MONO (230 4310);
FORCEPROP 0 LAST $SEC 1
J 0
(275 4575);
DISPLAY 0.680851 (275 4575);
PAINT MONO (275 4575);
DISPLAY INVISIBLE (275 4575);
FORCEPROP 0 LAST CDS_SEC 1
J 0
(275 4575);
DISPLAY 0.680851 (275 4575);
DISPLAY INVISIBLE (275 4575);
FORCEADD Q_RES..1
(1550 2125);
FORCEPROP 1 LAST WATTAGE 1/16W
J 2
(1525 1975);
DISPLAY 0.978723 (1525 1975);
FORCEPROP 1 LAST PART_NUMBER CS00002JB13
J 0
(1500 2225);
DISPLAY 0.978723 (1500 2225);
FORCEPROP 1 LAST PACK_TYPE 0402LF
J 0
(1800 1975);
DISPLAY 0.978723 (1800 1975);
FORCEPROP 1 LAST MATERIAL EMPTY
J 0
(1550 1975);
DISPLAY 0.978723 (1550 1975);
FORCEPROP 1 LAST TOLERANCE 5%
J 0
(1550 2025);
DISPLAY 0.978723 (1550 2025);
FORCEPROP 1 LAST VALUE 0
J 2
(1525 2025);
DISPLAY 0.978723 (1525 2025);
FORCEPROP 2 LAST CDS_LIB pure_quanta
J 0
(1550 2125);
DISPLAY INVISIBLE (1550 2125);
FORCEPROP 1 LAST PATH I71
J 0
(1500 2275);
DISPLAY 0.978723 (1500 2275);
PAINT WHITE (1500 2275);
DISPLAY INVISIBLE (1500 2275);
FORCEPROP 1 LAST LOCATION R315
J 0
(1500 2175);
DISPLAY 0.978723 (1500 2175);
FORCEPROP 1 LASTPIN (1450 2125) $PN 1
J 0
(1462 2137);
DISPLAY 0.787234 (1462 2137);
PAINT MONO (1462 2137);
FORCEPROP 1 LASTPIN (1650 2125) $PN 2
J 0
(1612 2137);
DISPLAY 0.787234 (1612 2137);
PAINT MONO (1612 2137);
FORCEPROP 0 LAST $SEC 1
J 0
(1500 2275);
DISPLAY 0.680851 (1500 2275);
PAINT MONO (1500 2275);
DISPLAY INVISIBLE (1500 2275);
FORCEPROP 0 LAST CDS_SEC 1
J 0
(1500 2275);
DISPLAY 0.680851 (1500 2275);
DISPLAY INVISIBLE (1500 2275);
FORCEADD Q_RES..1
(-2975 -275);
FORCEPROP 1 LAST WATTAGE 1/16W
J 2
(-3050 -350);
DISPLAY 0.978723 (-3050 -350);
FORCEPROP 1 LAST VALUE 0
J 2
(-3100 -250);
DISPLAY 0.978723 (-3100 -250);
FORCEPROP 1 LAST PACK_TYPE 0402LF
J 0
(-3025 -350);
DISPLAY 0.978723 (-3025 -350);
FORCEPROP 1 LAST MATERIAL CHIP
J 0
(-3375 -275);
DISPLAY 0.978723 (-3375 -275);
FORCEPROP 1 LAST TOLERANCE 5%
J 0
(-3375 -350);
DISPLAY 0.978723 (-3375 -350);
FORCEPROP 2 LAST CDS_LIB pure_quanta
J 0
(-2975 -275);
DISPLAY INVISIBLE (-2975 -275);
FORCEPROP 1 LAST PATH I72
J 0
(-3025 -125);
DISPLAY 0.978723 (-3025 -125);
PAINT WHITE (-3025 -125);
DISPLAY INVISIBLE (-3025 -125);
FORCEPROP 1 LAST PART_NUMBER CS00002JB13
J 0
(-3200 -175);
DISPLAY 0.978723 (-3200 -175);
DISPLAY INVISIBLE (-3200 -175);
FORCEPROP 1 LAST LOCATION R49
J 0
(-2850 -275);
DISPLAY 0.978723 (-2850 -275);
FORCEPROP 1 LASTPIN (-3075 -275) $PN 1
J 0
(-3063 -263);
DISPLAY 0.787234 (-3063 -263);
PAINT MONO (-3063 -263);
FORCEPROP 1 LASTPIN (-2875 -275) $PN 2
J 0
(-2913 -263);
DISPLAY 0.787234 (-2913 -263);
PAINT MONO (-2913 -263);
FORCEPROP 0 LAST $SEC 1
J 0
(-3025 -125);
DISPLAY 0.680851 (-3025 -125);
PAINT MONO (-3025 -125);
DISPLAY INVISIBLE (-3025 -125);
FORCEPROP 0 LAST CDS_SEC 1
J 0
(-3025 -125);
DISPLAY 0.680851 (-3025 -125);
DISPLAY INVISIBLE (-3025 -125);
FORCEADD OFFPAGE..4
R 2
(-4250 -275);
FORCEPROP 2 LAST $XR1 36 
J 0
(-4561 -275);
DISPLAY 0.638298 (-4561 -275);
PAINT MONO (-4561 -275);
FORCEPROP 2 LAST $XR0 56 
J 0
(-4471 -275);
DISPLAY 0.638298 (-4471 -275);
PAINT MONO (-4471 -275);
FORCEPROP 2 LAST CDS_LIB standard
J 0
(-4250 -275);
DISPLAY INVISIBLE (-4250 -275);
FORCEPROP 1 LAST OFFPAGE TRUE
J 2
(-4575 -400);
DISPLAY 0.872340 (-4575 -400);
PAINT GREEN (-4575 -400);
DISPLAY INVISIBLE (-4575 -400);
FORCEPROP 1 LAST COMMENT_BODY TRUE
J 2
(-4225 -375);
DISPLAY 0.872340 (-4225 -375);
PAINT PEACH (-4225 -375);
DISPLAY INVISIBLE (-4225 -375);
FORCEPROP 2 LAST PATH I73
J 0
(-4450 -225);
DISPLAY 0.680851 (-4450 -225);
DISPLAY INVISIBLE (-4450 -225);
FORCEADD Q_RES..1
(-2975 -175);
FORCEPROP 1 LAST MATERIAL CHIP
J 0
(-3375 -175);
DISPLAY 0.978723 (-3375 -175);
FORCEPROP 1 LAST VALUE 0
J 2
(-3100 -150);
DISPLAY 0.978723 (-3100 -150);
FORCEPROP 1 LAST PART_NUMBER CS00002JB13
J 0
(-3200 -75);
DISPLAY 0.978723 (-3200 -75);
FORCEPROP 2 LAST CDS_LIB pure_quanta
J 0
(-2975 -175);
DISPLAY INVISIBLE (-2975 -175);
FORCEPROP 1 LAST TOLERANCE 5%
J 0
(-3375 -250);
DISPLAY 0.978723 (-3375 -250);
DISPLAY INVISIBLE (-3375 -250);
FORCEPROP 1 LAST PATH I74
J 0
(-3025 -25);
DISPLAY 0.978723 (-3025 -25);
PAINT WHITE (-3025 -25);
DISPLAY INVISIBLE (-3025 -25);
FORCEPROP 1 LAST WATTAGE 1/16W
J 2
(-3050 -250);
DISPLAY 0.978723 (-3050 -250);
DISPLAY INVISIBLE (-3050 -250);
FORCEPROP 1 LAST PACK_TYPE 0402LF
J 0
(-3025 -250);
DISPLAY 0.978723 (-3025 -250);
DISPLAY INVISIBLE (-3025 -250);
FORCEPROP 1 LAST LOCATION R451
J 0
(-2850 -175);
DISPLAY 0.978723 (-2850 -175);
FORCEPROP 1 LASTPIN (-3075 -175) $PN 1
J 0
(-3063 -163);
DISPLAY 0.787234 (-3063 -163);
PAINT MONO (-3063 -163);
FORCEPROP 1 LASTPIN (-2875 -175) $PN 2
J 0
(-2913 -163);
DISPLAY 0.787234 (-2913 -163);
PAINT MONO (-2913 -163);
FORCEPROP 0 LAST $SEC 1
J 0
(-3025 -25);
DISPLAY 0.680851 (-3025 -25);
PAINT MONO (-3025 -25);
DISPLAY INVISIBLE (-3025 -25);
FORCEPROP 0 LAST CDS_SEC 1
J 0
(-3025 -25);
DISPLAY 0.680851 (-3025 -25);
DISPLAY INVISIBLE (-3025 -25);
FORCEADD OFFPAGE..5
(-4250 -175);
FORCEPROP 2 LAST $XR0 22 
J 0
(-4474 -175);
DISPLAY 0.638298 (-4474 -175);
PAINT MONO (-4474 -175);
FORCEPROP 2 LAST CDS_LIB standard
J 0
(-4250 -175);
DISPLAY INVISIBLE (-4250 -175);
FORCEPROP 1 LAST OFFPAGE TRUE
J 0
(-3925 -300);
DISPLAY 0.872340 (-3925 -300);
PAINT GREEN (-3925 -300);
DISPLAY INVISIBLE (-3925 -300);
FORCEPROP 1 LAST COMMENT_BODY TRUE
J 0
(-4150 -250);
DISPLAY 0.872340 (-4150 -250);
PAINT PEACH (-4150 -250);
DISPLAY INVISIBLE (-4150 -250);
FORCEPROP 2 LAST PATH I76
J 0
(-4500 -125);
DISPLAY 0.680851 (-4500 -125);
DISPLAY INVISIBLE (-4500 -125);
FORCEADD OFFPAGE..1
(-4475 2250);
FORCEPROP 2 LAST $XR0 35 
J 0
(-4726 2250);
DISPLAY 0.638298 (-4726 2250);
PAINT MONO (-4726 2250);
FORCEPROP 2 LAST PATH I79
J 0
(-4675 2300);
DISPLAY 0.680851 (-4675 2300);
DISPLAY INVISIBLE (-4675 2300);
FORCEPROP 1 LAST COMMENT_BODY TRUE
J 0
(-4345 2150);
DISPLAY 1.106383 (-4345 2150);
PAINT PEACH (-4345 2150);
DISPLAY INVISIBLE (-4345 2150);
FORCEPROP 1 LAST OFFPAGE TRUE
J 0
(-4145 2120);
PAINT GREEN (-4145 2120);
DISPLAY INVISIBLE (-4145 2120);
FORCEPROP 2 LAST CDS_LIB standard
J 0
(-4475 2250);
DISPLAY 0.808511 (-4475 2250);
PAINT MONO (-4475 2250);
DISPLAY INVISIBLE (-4475 2250);
FORCEADD Q_RES..1
(3225 3750);
FORCEPROP 1 LAST WATTAGE 1/16W
J 2
(3200 3600);
DISPLAY 0.978723 (3200 3600);
FORCEPROP 1 LAST VALUE 47K
J 2
(3200 3650);
DISPLAY 0.978723 (3200 3650);
FORCEPROP 1 LAST TOLERANCE 1%
J 0
(3225 3650);
DISPLAY 0.978723 (3225 3650);
FORCEPROP 1 LAST MATERIAL CHIP
J 0
(3225 3600);
DISPLAY 0.978723 (3225 3600);
FORCEPROP 1 LAST PACK_TYPE 0402LF
J 0
(3475 3600);
DISPLAY 0.978723 (3475 3600);
FORCEPROP 1 LAST PART_NUMBER CS34702FB01
J 0
(3175 3850);
DISPLAY 0.978723 (3175 3850);
FORCEPROP 2 LAST CDS_LIB pure_quanta
J 0
(3225 3750);
DISPLAY INVISIBLE (3225 3750);
FORCEPROP 1 LAST PATH I8
J 0
(3175 3900);
DISPLAY 0.978723 (3175 3900);
PAINT WHITE (3175 3900);
DISPLAY INVISIBLE (3175 3900);
FORCEPROP 1 LAST LOCATION R290
J 0
(3175 3800);
DISPLAY 0.978723 (3175 3800);
FORCEPROP 1 LASTPIN (3125 3750) $PN 1
J 0
(3137 3762);
DISPLAY 0.787234 (3137 3762);
PAINT MONO (3137 3762);
FORCEPROP 1 LASTPIN (3325 3750) $PN 2
J 0
(3287 3762);
DISPLAY 0.787234 (3287 3762);
PAINT MONO (3287 3762);
FORCEPROP 0 LAST $SEC 1
J 0
(3175 3900);
DISPLAY 0.680851 (3175 3900);
PAINT MONO (3175 3900);
DISPLAY INVISIBLE (3175 3900);
FORCEPROP 0 LAST CDS_SEC 1
J 0
(3175 3900);
DISPLAY 0.680851 (3175 3900);
DISPLAY INVISIBLE (3175 3900);
FORCEADD UNIVERSAL_POWER..1
(-1725 3250);
FORCEPROP 3 LASTPIN (-1725 3200) SIG_NAME P3V3_AUX\g
J 0
(-1715 3210);
DISPLAY 0.659574 (-1715 3210);
PAINT MONO (-1715 3210);
DISPLAY INVISIBLE (-1715 3210);
FORCEPROP 1 LAST HDL_POWER P3V3_AUX
J 1
(-1725 3300);
DISPLAY 0.702128 (-1725 3300);
PAINT GREEN (-1725 3300);
FORCEPROP 2 LAST CDS_LIB logical_power
J 0
(-1725 3250);
DISPLAY INVISIBLE (-1725 3250);
FORCEPROP 1 LAST PATH I80
J 0
(-1675 3275);
DISPLAY 0.872340 (-1675 3275);
PAINT AQUA (-1675 3275);
DISPLAY INVISIBLE (-1675 3275);
FORCEADD Q_RES..2
(-1725 3050);
FORCEPROP 1 LAST PACK_TYPE 0402LF
J 0
(-1700 2925);
DISPLAY 0.510638 (-1700 2925);
PAINT SKYBLUE (-1700 2925);
FORCEPROP 1 LAST VALUE 1K
J 0
(-1680 3125);
DISPLAY 0.510638 (-1680 3125);
PAINT SKYBLUE (-1680 3125);
FORCEPROP 1 LAST WATTAGE 1/16W
J 0
(-1685 3025);
DISPLAY 0.510638 (-1685 3025);
PAINT SKYBLUE (-1685 3025);
FORCEPROP 1 LAST TOLERANCE 1%
J 0
(-1680 3075);
DISPLAY 0.510638 (-1680 3075);
PAINT SKYBLUE (-1680 3075);
FORCEPROP 1 LAST MATERIAL EMPTY
J 0
(-1685 2975);
DISPLAY 0.510638 (-1685 2975);
PAINT RED (-1685 2975);
FORCEPROP 2 LAST CDS_LIB pure_quanta
J 0
(-1725 3050);
DISPLAY INVISIBLE (-1725 3050);
FORCEPROP 2 LAST SEC_TYPE 0402LF
J 0
(-1675 3275);
DISPLAY 0.680851 (-1675 3275);
DISPLAY INVISIBLE (-1675 3275);
FORCEPROP 1 LAST PATH I81
J 0
(-1675 3225);
DISPLAY 0.978723 (-1675 3225);
PAINT WHITE (-1675 3225);
DISPLAY INVISIBLE (-1675 3225);
FORCEPROP 1 LAST PART_NUMBER CS21002FB06
J 0
(-1685 2925);
DISPLAY 0.510638 (-1685 2925);
PAINT WHITE (-1685 2925);
DISPLAY INVISIBLE (-1685 2925);
FORCEPROP 1 LAST LOCATION R633
J 0
(-1680 3175);
DISPLAY 0.702128 (-1680 3175);
PAINT YELLOW (-1680 3175);
FORCEPROP 1 LASTPIN (-1725 3150) $PN 1
J 0
(-1720 3112);
DISPLAY 0.808511 (-1720 3112);
PAINT WHITE (-1720 3112);
FORCEPROP 1 LASTPIN (-1725 2950) $PN 2
J 0
(-1720 2960);
DISPLAY 0.808511 (-1720 2960);
PAINT WHITE (-1720 2960);
FORCEPROP 2 LAST SEC 1
J 0
(-1675 3275);
DISPLAY 0.680851 (-1675 3275);
PAINT MONO (-1675 3275);
DISPLAY INVISIBLE (-1675 3275);
FORCEADD UNIVERSAL_POWER..1
(-2600 525);
FORCEPROP 3 LASTPIN (-2600 475) SIG_NAME P3V3_AUX\g
J 0
(-2590 485);
DISPLAY 0.659574 (-2590 485);
PAINT MONO (-2590 485);
DISPLAY INVISIBLE (-2590 485);
FORCEPROP 1 LAST HDL_POWER P3V3_AUX
J 1
(-2600 575);
DISPLAY 0.702128 (-2600 575);
PAINT GREEN (-2600 575);
FORCEPROP 2 LAST CDS_LIB logical_power
J 0
(-2600 525);
DISPLAY INVISIBLE (-2600 525);
FORCEPROP 1 LAST PATH I82
J 0
(-2550 550);
DISPLAY 0.872340 (-2550 550);
PAINT AQUA (-2550 550);
DISPLAY INVISIBLE (-2550 550);
FORCEADD Q_RES..2
(-2600 200);
FORCEPROP 1 LAST PACK_TYPE 0402LF
J 0
(-2560 25);
DISPLAY 0.978723 (-2560 25);
FORCEPROP 1 LAST PART_NUMBER CS22002FB07
J 0
(-2560 75);
DISPLAY 0.978723 (-2560 75);
FORCEPROP 1 LAST MATERIAL CHIP
J 0
(-2560 125);
DISPLAY 0.978723 (-2560 125);
FORCEPROP 1 LAST WATTAGE 1/16W
J 0
(-2560 175);
DISPLAY 0.978723 (-2560 175);
FORCEPROP 1 LAST VALUE 2K
J 0
(-2555 275);
DISPLAY 0.978723 (-2555 275);
FORCEPROP 1 LAST TOLERANCE 1%
J 0
(-2555 225);
DISPLAY 0.978723 (-2555 225);
FORCEPROP 2 LAST CDS_LIB pure_quanta
J 0
(-2600 200);
DISPLAY INVISIBLE (-2600 200);
FORCEPROP 1 LAST PATH I83
J 0
(-2550 375);
DISPLAY 0.978723 (-2550 375);
PAINT WHITE (-2550 375);
DISPLAY INVISIBLE (-2550 375);
FORCEPROP 1 LAST LOCATION R751
J 0
(-2555 325);
DISPLAY 0.978723 (-2555 325);
FORCEPROP 1 LASTPIN (-2600 300) $PN 1
J 0
(-2595 262);
DISPLAY 0.787234 (-2595 262);
PAINT MONO (-2595 262);
FORCEPROP 1 LASTPIN (-2600 100) $PN 2
J 0
(-2595 110);
DISPLAY 0.787234 (-2595 110);
PAINT MONO (-2595 110);
FORCEPROP 0 LAST $SEC 1
J 0
(-2550 375);
DISPLAY 0.680851 (-2550 375);
PAINT MONO (-2550 375);
DISPLAY INVISIBLE (-2550 375);
FORCEPROP 0 LAST CDS_SEC 1
J 0
(-2550 375);
DISPLAY 0.680851 (-2550 375);
DISPLAY INVISIBLE (-2550 375);
FORCEADD UNIVERSAL_POWER..1
(-575 4700);
FORCEPROP 3 LASTPIN (-575 4650) SIG_NAME P3V3_RGM\g
J 0
(-565 4660);
DISPLAY 0.659574 (-565 4660);
PAINT MONO (-565 4660);
DISPLAY INVISIBLE (-565 4660);
FORCEPROP 1 LAST HDL_POWER P3V3_RGM
J 1
(-575 4750);
DISPLAY 0.702128 (-575 4750);
PAINT GREEN (-575 4750);
FORCEPROP 2 LAST CDS_LIB logical_power
J 0
(-575 4700);
DISPLAY INVISIBLE (-575 4700);
FORCEPROP 1 LAST PATH I84
J 0
(-525 4725);
DISPLAY 0.872340 (-525 4725);
PAINT AQUA (-525 4725);
DISPLAY INVISIBLE (-525 4725);
FORCEADD UNIVERSAL_POWER..1
(225 4825);
FORCEPROP 3 LASTPIN (225 4775) SIG_NAME P3V3_RGM\g
J 0
(235 4785);
DISPLAY 0.659574 (235 4785);
PAINT MONO (235 4785);
DISPLAY INVISIBLE (235 4785);
FORCEPROP 1 LAST HDL_POWER P3V3_RGM
J 1
(225 4875);
DISPLAY 0.702128 (225 4875);
PAINT GREEN (225 4875);
FORCEPROP 2 LAST CDS_LIB logical_power
J 0
(225 4825);
DISPLAY INVISIBLE (225 4825);
FORCEPROP 1 LAST PATH I85
J 0
(275 4850);
DISPLAY 0.872340 (275 4850);
PAINT AQUA (275 4850);
DISPLAY INVISIBLE (275 4850);
FORCEADD 74LVC2G07DW7..1
(-1275 1050);
FORCEPROP 2 LAST VALUE 74LVC2G07DW-7
J 0
(-1425 1475);
DISPLAY 0.680851 (-1425 1475);
FORCEPROP 1 LAST PART_NUMBER AL002G07003
J 0
(-1444 1284);
DISPLAY 0.723404 (-1444 1284);
PAINT GREEN (-1444 1284);
FORCEPROP 1 LAST MATERIAL IC
J 0
(-1444 1157);
DISPLAY 0.723404 (-1444 1157);
PAINT GREEN (-1444 1157);
FORCEPROP 2 LAST PART_TYPE SMLF
J 0
(-1425 1525);
DISPLAY 0.680851 (-1425 1525);
FORCEPROP 1 LAST CDS_LMAN_SYM_OUTLINE -175,100,175,-100
J 0
(-1275 1050);
DISPLAY 0.468085 (-1275 1050);
PAINT GREEN (-1275 1050);
DISPLAY INVISIBLE (-1275 1050);
FORCEPROP 1 LAST NEEDS_NO_SIZE TRUE
J 0
(-1275 1050);
DISPLAY 0.723404 (-1275 1050);
PAINT GREEN (-1275 1050);
DISPLAY INVISIBLE (-1275 1050);
FORCEPROP 1 LAST PATH I87
J 0
(-1275 1050);
DISPLAY 0.723404 (-1275 1050);
PAINT GREEN (-1275 1050);
DISPLAY INVISIBLE (-1275 1050);
FORCEPROP 2 LAST CDS_LIB pure_quanta
J 0
(-1275 1050);
DISPLAY INVISIBLE (-1275 1050);
FORCEPROP 1 LAST LOCATION U6
J 0
(-1444 1431);
DISPLAY 0.723404 (-1444 1431);
PAINT GREEN (-1444 1431);
FORCEPROP 0 LASTPIN (-1600 1100) $PN 1
J 2
(-1610 1110);
DISPLAY 0.680851 (-1610 1110);
PAINT MONO (-1610 1110);
FORCEPROP 0 LASTPIN (-950 1100) $PN 6
J 0
(-940 1110);
DISPLAY 0.680851 (-940 1110);
PAINT MONO (-940 1110);
FORCEPROP 0 LASTPIN (-1600 1000) $PN 3
J 2
(-1610 1010);
DISPLAY 0.680851 (-1610 1010);
PAINT MONO (-1610 1010);
FORCEPROP 0 LASTPIN (-950 1000) $PN 4
J 0
(-940 1010);
DISPLAY 0.680851 (-940 1010);
PAINT MONO (-940 1010);
FORCEPROP 0 LASTPIN (-1600 1050) $PN 2
J 2
(-1610 1060);
DISPLAY 0.680851 (-1610 1060);
PAINT MONO (-1610 1060);
FORCEPROP 0 LASTPIN (-950 1050) $PN 5
J 0
(-940 1060);
DISPLAY 0.680851 (-940 1060);
PAINT MONO (-940 1060);
FORCEPROP 0 LAST $SEC 1
J 0
(-1425 1575);
DISPLAY 0.680851 (-1425 1575);
PAINT MONO (-1425 1575);
DISPLAY INVISIBLE (-1425 1575);
FORCEPROP 0 LAST CDS_SEC 1
J 0
(-1425 1575);
DISPLAY 0.680851 (-1425 1575);
DISPLAY INVISIBLE (-1425 1575);
FORCEADD MC74VHC1G07DFT2G..1
(3125 2125);
FORCEPROP 1 LAST MATERIAL EMPTY
J 0
(2780 2282);
DISPLAY 0.723404 (2780 2282);
PAINT GREEN (2780 2282);
FORCEPROP 2 LAST PART_TYPE SMLF
J 0
(2800 2650);
DISPLAY 0.680851 (2800 2650);
FORCEPROP 1 LAST PART_NUMBER AL001G07003
J 0
(2780 2409);
DISPLAY 0.723404 (2780 2409);
PAINT GREEN (2780 2409);
FORCEPROP 2 LAST VALUE MC74VHC1G07DFT2G
J 0
(2800 2600);
DISPLAY 0.680851 (2800 2600);
FORCEPROP 2 LAST CDS_LIB pure_quanta
J 0
(3125 2125);
DISPLAY INVISIBLE (3125 2125);
FORCEPROP 1 LAST PATH I89
J 0
(3125 2125);
DISPLAY 0.723404 (3125 2125);
PAINT GREEN (3125 2125);
DISPLAY INVISIBLE (3125 2125);
FORCEPROP 1 LAST NEEDS_NO_SIZE TRUE
J 0
(3125 2125);
DISPLAY 0.723404 (3125 2125);
PAINT GREEN (3125 2125);
DISPLAY INVISIBLE (3125 2125);
FORCEPROP 1 LAST CDS_LMAN_SYM_OUTLINE -350,150,350,-150
J 0
(3125 2125);
DISPLAY 0.468085 (3125 2125);
PAINT GREEN (3125 2125);
DISPLAY INVISIBLE (3125 2125);
FORCEPROP 1 LAST LOCATION U13
J 0
(2780 2556);
DISPLAY 0.723404 (2780 2556);
PAINT GREEN (2780 2556);
FORCEPROP 0 LASTPIN (2625 2025) $PN 3
J 2
(2615 2035);
DISPLAY 0.680851 (2615 2035);
PAINT MONO (2615 2035);
FORCEPROP 0 LASTPIN (2625 2125) $PN 2
J 2
(2615 2135);
DISPLAY 0.680851 (2615 2135);
PAINT MONO (2615 2135);
FORCEPROP 0 LASTPIN (2625 2225) $PN 1
J 2
(2615 2235);
DISPLAY 0.680851 (2615 2235);
PAINT MONO (2615 2235);
FORCEPROP 0 LASTPIN (3625 2025) $PN 4
J 0
(3635 2035);
DISPLAY 0.680851 (3635 2035);
PAINT MONO (3635 2035);
FORCEPROP 0 LASTPIN (3625 2225) $PN 5
J 0
(3635 2235);
DISPLAY 0.680851 (3635 2235);
PAINT MONO (3635 2235);
FORCEPROP 0 LAST $SEC 1
J 0
(2800 2700);
DISPLAY 0.680851 (2800 2700);
PAINT MONO (2800 2700);
DISPLAY INVISIBLE (2800 2700);
FORCEPROP 0 LAST CDS_SEC 1
J 0
(2800 2700);
DISPLAY 0.680851 (2800 2700);
DISPLAY INVISIBLE (2800 2700);
FORCEADD Q_RES..2
(4000 4050);
FORCEPROP 1 LAST VALUE 4.7K
J 0
(4045 4125);
DISPLAY 0.978723 (4045 4125);
FORCEPROP 1 LAST TOLERANCE 1%
J 0
(4045 4075);
DISPLAY 0.978723 (4045 4075);
FORCEPROP 1 LAST WATTAGE 1/16W
J 0
(4040 4025);
DISPLAY 0.978723 (4040 4025);
FORCEPROP 1 LAST MATERIAL CHIP
J 0
(4040 3975);
DISPLAY 0.978723 (4040 3975);
FORCEPROP 1 LAST PACK_TYPE 0402LF
J 0
(4040 3875);
DISPLAY 0.978723 (4040 3875);
FORCEPROP 1 LAST PART_NUMBER CS24702FB06
J 0
(4040 3925);
DISPLAY 0.978723 (4040 3925);
FORCEPROP 2 LAST CDS_LIB pure_quanta
J 0
(4000 4050);
DISPLAY INVISIBLE (4000 4050);
FORCEPROP 1 LAST PATH I9
J 0
(4050 4225);
DISPLAY 0.978723 (4050 4225);
PAINT WHITE (4050 4225);
DISPLAY INVISIBLE (4050 4225);
FORCEPROP 1 LAST LOCATION R291
J 0
(4045 4175);
DISPLAY 0.978723 (4045 4175);
FORCEPROP 1 LASTPIN (4000 4150) $PN 1
J 0
(4005 4112);
DISPLAY 0.787234 (4005 4112);
PAINT MONO (4005 4112);
FORCEPROP 1 LASTPIN (4000 3950) $PN 2
J 0
(4005 3960);
DISPLAY 0.787234 (4005 3960);
PAINT MONO (4005 3960);
FORCEPROP 0 LAST $SEC 1
J 0
(4050 4225);
DISPLAY 0.680851 (4050 4225);
PAINT MONO (4050 4225);
DISPLAY INVISIBLE (4050 4225);
FORCEPROP 0 LAST CDS_SEC 1
J 0
(4050 4225);
DISPLAY 0.680851 (4050 4225);
DISPLAY INVISIBLE (4050 4225);
FORCEADD TPS3808G18DBVR..1
(-1125 -225);
FORCEPROP 2 LAST VALUE TPS3808G01DBVR
J 0
(-1375 25);
DISPLAY 0.680851 (-1375 25);
FORCEPROP 1 LAST PART_NUMBER AL003808005
J 0
(-1324 -65);
DISPLAY 0.723404 (-1324 -65);
PAINT GREEN (-1324 -65);
FORCEPROP 2 LAST PART_TYPE SMLF
J 0
(-1375 75);
DISPLAY 0.680851 (-1375 75);
FORCEPROP 1 LAST MATERIAL IC
J 0
(-1324 -115);
DISPLAY 0.723404 (-1324 -115);
PAINT GREEN (-1324 -115);
FORCEPROP 1 LAST CDS_LMAN_SYM_OUTLINE -200,100,200,-100
J 0
(-1125 -225);
DISPLAY 0.468085 (-1125 -225);
PAINT GREEN (-1125 -225);
DISPLAY INVISIBLE (-1125 -225);
FORCEPROP 1 LAST NEEDS_NO_SIZE TRUE
J 0
(-925 -225);
DISPLAY 0.468085 (-925 -225);
PAINT GREEN (-925 -225);
DISPLAY INVISIBLE (-925 -225);
FORCEPROP 1 LAST PATH I90
J 0
(-1125 -225);
DISPLAY 0.723404 (-1125 -225);
PAINT GREEN (-1125 -225);
DISPLAY INVISIBLE (-1125 -225);
FORCEPROP 2 LAST CDS_LIB pure_quanta
J 0
(-1125 -225);
DISPLAY INVISIBLE (-1125 -225);
FORCEPROP 1 LAST LOCATION U43
J 0
(-1324 -20);
DISPLAY 0.723404 (-1324 -20);
PAINT GREEN (-1324 -20);
FORCEPROP 0 LASTPIN (-1475 -275) $PN 3
J 2
(-1485 -265);
DISPLAY 0.680851 (-1485 -265);
PAINT MONO (-1485 -265);
FORCEPROP 0 LASTPIN (-1475 -175) $PN 1
J 2
(-1485 -165);
DISPLAY 0.680851 (-1485 -165);
PAINT MONO (-1485 -165);
FORCEPROP 0 LASTPIN (-775 -275) $PN 4
J 0
(-765 -265);
DISPLAY 0.680851 (-765 -265);
PAINT MONO (-765 -265);
FORCEPROP 0 LASTPIN (-1475 -225) $PN 2
J 2
(-1485 -215);
DISPLAY 0.680851 (-1485 -215);
PAINT MONO (-1485 -215);
FORCEPROP 0 LASTPIN (-775 -225) $PN 5
J 0
(-765 -215);
DISPLAY 0.680851 (-765 -215);
PAINT MONO (-765 -215);
FORCEPROP 0 LASTPIN (-775 -175) $PN 6
J 0
(-765 -165);
DISPLAY 0.680851 (-765 -165);
PAINT MONO (-765 -165);
FORCEPROP 0 LAST $SEC 1
J 0
(-1300 125);
DISPLAY 0.680851 (-1300 125);
PAINT MONO (-1300 125);
DISPLAY INVISIBLE (-1300 125);
FORCEPROP 0 LAST CDS_SEC 1
J 0
(-1300 125);
DISPLAY 0.680851 (-1300 125);
DISPLAY INVISIBLE (-1300 125);
FORCEADD OFFPAGE..1
(-4200 1000);
FORCEPROP 2 LAST $XR0 34 
J 0
(-4421 1000);
DISPLAY 0.638298 (-4421 1000);
PAINT MONO (-4421 1000);
FORCEPROP 2 LAST PATH I91
J 0
(-4400 1050);
DISPLAY 0.680851 (-4400 1050);
DISPLAY INVISIBLE (-4400 1050);
FORCEPROP 2 LAST CDS_LIB standard
J 0
(-4200 1000);
DISPLAY INVISIBLE (-4200 1000);
FORCEPROP 1 LAST OFFPAGE TRUE
J 0
(-3875 875);
DISPLAY 0.872340 (-3875 875);
PAINT GREEN (-3875 875);
DISPLAY INVISIBLE (-3875 875);
FORCEPROP 1 LAST COMMENT_BODY TRUE
J 0
(-4075 900);
DISPLAY 0.872340 (-4075 900);
PAINT PEACH (-4075 900);
DISPLAY INVISIBLE (-4075 900);
FORCEADD Q_RES..1
(-3075 1000);
FORCEPROP 1 LAST VALUE 33.2
J 0
(-2975 1000);
DISPLAY 0.510638 (-2975 1000);
PAINT SKYBLUE (-2975 1000);
FORCEPROP 1 LAST MATERIAL CHIP
J 0
(-2850 1000);
DISPLAY 0.510638 (-2850 1000);
PAINT SKYBLUE (-2850 1000);
FORCEPROP 1 LAST PACK_TYPE 0402LF
J 0
(-2825 850);
DISPLAY 0.510638 (-2825 850);
PAINT SKYBLUE (-2825 850);
DISPLAY INVISIBLE (-2825 850);
FORCEPROP 1 LAST WATTAGE 1/16W
J 2
(-3100 850);
DISPLAY 0.510638 (-3100 850);
PAINT SKYBLUE (-3100 850);
DISPLAY INVISIBLE (-3100 850);
FORCEPROP 1 LAST PART_NUMBER CS03322FB03
J 0
(-3125 1100);
DISPLAY 0.510638 (-3125 1100);
PAINT WHITE (-3125 1100);
DISPLAY INVISIBLE (-3125 1100);
FORCEPROP 1 LAST TOLERANCE 1%
J 0
(-2950 1000);
DISPLAY 0.510638 (-2950 1000);
PAINT SKYBLUE (-2950 1000);
DISPLAY INVISIBLE (-2950 1000);
FORCEPROP 1 LAST PATH I92
J 0
(-3125 1150);
DISPLAY 0.978723 (-3125 1150);
PAINT WHITE (-3125 1150);
DISPLAY INVISIBLE (-3125 1150);
FORCEPROP 2 LAST CDS_LIB pure_quanta
J 0
(-3075 1000);
DISPLAY INVISIBLE (-3075 1000);
FORCEPROP 1 LAST $LOCATION R388
J 0
(-3300 1000);
DISPLAY 0.702128 (-3300 1000);
PAINT YELLOW (-3300 1000);
FORCEPROP 1 LASTPIN (-3175 1000) $PN 1
J 0
(-3163 1012);
DISPLAY 0.787234 (-3163 1012);
PAINT MONO (-3163 1012);
FORCEPROP 1 LASTPIN (-2975 1000) $PN 2
J 0
(-3013 1012);
DISPLAY 0.787234 (-3013 1012);
PAINT MONO (-3013 1012);
FORCEPROP 0 LAST CDS_LOCATION R388
J 0
(-3300 1050);
DISPLAY 0.680851 (-3300 1050);
DISPLAY INVISIBLE (-3300 1050);
FORCEPROP 0 LAST $SEC 1
J 0
(-3300 1050);
DISPLAY 0.680851 (-3300 1050);
PAINT MONO (-3300 1050);
DISPLAY INVISIBLE (-3300 1050);
FORCEPROP 0 LAST CDS_SEC 1
J 0
(-3300 1050);
DISPLAY 0.680851 (-3300 1050);
DISPLAY INVISIBLE (-3300 1050);
FORCEADD MC74VHC1G32DTT1G..1
(-2475 2475);
FORCEPROP 1 LAST PART_NUMBER AL001G32031
J 0
(-2870 2884);
DISPLAY 0.723404 (-2870 2884);
PAINT GREEN (-2870 2884);
FORCEPROP 1 LAST MATERIAL IC
J 0
(-2870 2757);
DISPLAY 0.723404 (-2870 2757);
PAINT GREEN (-2870 2757);
FORCEPROP 2 LAST PART_TYPE SMLF
J 0
(-2875 3050);
DISPLAY 0.680851 (-2875 3050);
FORCEPROP 2 LAST VALUE MC74VHC1G32DTT1G
J 0
(-2875 3000);
DISPLAY 0.680851 (-2875 3000);
FORCEPROP 2 LAST CDS_LIB pure_quanta
J 0
(-2475 2475);
DISPLAY INVISIBLE (-2475 2475);
FORCEPROP 1 LAST PATH I94
J 0
(-2475 2475);
DISPLAY 0.723404 (-2475 2475);
PAINT GREEN (-2475 2475);
DISPLAY INVISIBLE (-2475 2475);
FORCEPROP 1 LAST CDS_LMAN_SYM_OUTLINE -400,275,400,-275
J 0
(-2475 2475);
DISPLAY 0.468085 (-2475 2475);
PAINT GREEN (-2475 2475);
DISPLAY INVISIBLE (-2475 2475);
FORCEPROP 1 LAST NEEDS_NO_SIZE TRUE
J 0
(-2475 2475);
DISPLAY 0.723404 (-2475 2475);
PAINT GREEN (-2475 2475);
DISPLAY INVISIBLE (-2475 2475);
FORCEPROP 1 LAST $LOCATION U58
J 0
(-2875 3100);
DISPLAY 0.723404 (-2875 3100);
PAINT GREEN (-2875 3100);
FORCEPROP 0 LASTPIN (-3025 2300) $PN 3
J 2
(-3035 2310);
DISPLAY 0.680851 (-3035 2310);
PAINT MONO (-3035 2310);
FORCEPROP 0 LASTPIN (-3025 2450) $PN 2
J 2
(-3035 2460);
DISPLAY 0.680851 (-3035 2460);
PAINT MONO (-3035 2460);
FORCEPROP 0 LASTPIN (-3025 2650) $PN 1
J 2
(-3035 2660);
DISPLAY 0.680851 (-3035 2660);
PAINT MONO (-3035 2660);
FORCEPROP 0 LASTPIN (-1925 2300) $PN 4
J 0
(-1915 2310);
DISPLAY 0.680851 (-1915 2310);
PAINT MONO (-1915 2310);
FORCEPROP 0 LASTPIN (-1925 2650) $PN 5
J 0
(-1915 2660);
DISPLAY 0.680851 (-1915 2660);
PAINT MONO (-1915 2660);
FORCEPROP 0 LAST CDS_LOCATION U58
J 0
(-2875 3100);
DISPLAY 0.680851 (-2875 3100);
DISPLAY INVISIBLE (-2875 3100);
FORCEPROP 0 LAST $SEC 1
J 0
(-2875 3100);
DISPLAY 0.680851 (-2875 3100);
PAINT MONO (-2875 3100);
DISPLAY INVISIBLE (-2875 3100);
FORCEPROP 0 LAST CDS_SEC 1
J 0
(-2875 3100);
DISPLAY 0.680851 (-2875 3100);
DISPLAY INVISIBLE (-2875 3100);
FORCEADD UNIVERSAL_GND..1
(-3025 2150);
FORCEPROP 3 LASTPIN (-3025 2200) SIG_NAME GND\g
J 0
(-3015 2210);
DISPLAY 0.659574 (-3015 2210);
PAINT MONO (-3015 2210);
DISPLAY INVISIBLE (-3015 2210);
FORCEPROP 1 LAST HDL_POWER GND
J 1
(-3000 2075);
DISPLAY 0.702128 (-3000 2075);
PAINT GREEN (-3000 2075);
DISPLAY INVISIBLE (-3000 2075);
FORCEPROP 1 LAST PATH I95
J 0
(-2950 2150);
DISPLAY 0.872340 (-2950 2150);
PAINT AQUA (-2950 2150);
DISPLAY INVISIBLE (-2950 2150);
FORCEPROP 2 LAST CDS_LIB logical_power
J 0
(-3025 2150);
DISPLAY INVISIBLE (-3025 2150);
FORCEADD UNIVERSAL_GND..1
(-2050 2900);
FORCEPROP 3 LASTPIN (-2050 2950) SIG_NAME GND\g
J 0
(-2040 2960);
DISPLAY 0.659574 (-2040 2960);
PAINT MONO (-2040 2960);
DISPLAY INVISIBLE (-2040 2960);
FORCEPROP 1 LAST HDL_POWER GND
J 1
(-2025 2825);
DISPLAY 0.702128 (-2025 2825);
PAINT GREEN (-2025 2825);
DISPLAY INVISIBLE (-2025 2825);
FORCEPROP 1 LAST PATH I96
J 0
(-1975 2900);
DISPLAY 0.872340 (-1975 2900);
PAINT AQUA (-1975 2900);
DISPLAY INVISIBLE (-1975 2900);
FORCEPROP 2 LAST CDS_LIB logical_power
J 0
(-2050 2900);
DISPLAY INVISIBLE (-2050 2900);
FORCEADD Q_CAP..1
R 2
(-2050 3125);
FORCEPROP 1 LAST TOLERANCE 10%
J 2
(-2100 3050);
DISPLAY 0.510638 (-2100 3050);
PAINT SKYBLUE (-2100 3050);
FORCEPROP 1 LAST PACK_TYPE 0402
J 2
(-2100 2950);
DISPLAY 0.510638 (-2100 2950);
PAINT SKYBLUE (-2100 2950);
FORCEPROP 1 LAST VALUE 0.1UF
J 2
(-2100 3150);
DISPLAY 0.510638 (-2100 3150);
PAINT SKYBLUE (-2100 3150);
FORCEPROP 1 LAST MATERIAL X7R
J 2
(-2100 3000);
DISPLAY 0.510638 (-2100 3000);
PAINT SKYBLUE (-2100 3000);
FORCEPROP 1 LAST PART_NUMBER CH4104K1B00
J 2
(-2100 2900);
DISPLAY 0.510638 (-2100 2900);
PAINT WHITE (-2100 2900);
FORCEPROP 1 LAST VOLTAGE 25V
J 2
(-2100 3100);
DISPLAY 0.510638 (-2100 3100);
PAINT SKYBLUE (-2100 3100);
FORCEPROP 1 LAST PATH I97
J 2
(-2100 3275);
DISPLAY 0.978723 (-2100 3275);
PAINT WHITE (-2100 3275);
DISPLAY INVISIBLE (-2100 3275);
FORCEPROP 2 LAST CDS_LIB pure_quanta
J 0
(-2050 3125);
DISPLAY INVISIBLE (-2050 3125);
FORCEPROP 1 LAST $LOCATION C337
J 2
(-2100 3225);
DISPLAY 0.978723 (-2100 3225);
FORCEPROP 1 LASTPIN (-2050 3225) $PN 1
J 2
(-2060 3205);
DISPLAY 0.787234 (-2060 3205);
PAINT MONO (-2060 3205);
FORCEPROP 1 LASTPIN (-2050 3025) $PN 2
J 2
(-2060 3005);
DISPLAY 0.787234 (-2060 3005);
PAINT MONO (-2060 3005);
FORCEPROP 0 LAST CDS_LOCATION C337
J 0
(-2100 3275);
DISPLAY 0.680851 (-2100 3275);
DISPLAY INVISIBLE (-2100 3275);
FORCEPROP 0 LAST $SEC 1
J 0
(-2100 3275);
DISPLAY 0.680851 (-2100 3275);
PAINT MONO (-2100 3275);
DISPLAY INVISIBLE (-2100 3275);
FORCEPROP 0 LAST CDS_SEC 1
J 0
(-2100 3275);
DISPLAY 0.680851 (-2100 3275);
DISPLAY INVISIBLE (-2100 3275);
FORCEADD VCCAUX15..1
(-2050 3375);
FORCEPROP 3 LASTPIN (-2050 3325) SIG_NAME P3V3_AUX\g
J 0
(-2040 3335);
DISPLAY 0.659574 (-2040 3335);
PAINT MONO (-2040 3335);
DISPLAY INVISIBLE (-2040 3335);
FORCEPROP 1 LAST HDL_POWER P3V3_AUX
J 1
(-2050 3425);
DISPLAY 0.553191 (-2050 3425);
PAINT GREEN (-2050 3425);
FORCEPROP 1 LAST PATH I98
J 0
(-2000 3400);
DISPLAY 0.872340 (-2000 3400);
PAINT AQUA (-2000 3400);
DISPLAY INVISIBLE (-2000 3400);
FORCEPROP 2 LAST CDS_LIB logical_power
J 0
(-2050 3375);
DISPLAY INVISIBLE (-2050 3375);
FORCEADD QUANTA_TITLE_BLOCK_C..1
(4650 -1425);
FORCEPROP 0 LAST CDS_CON_LAST_MODIFIED Fri Aug 25 17:25:40 2023
J 0
(2765 -1410);
DISPLAY INVISIBLE (2765 -1410);
FORCEPROP 2 LAST Q_DEPT 
J 1
(887 -1376);
DISPLAY 1.957447 (887 -1376);
PAINT GREEN (887 -1376);
FORCEPROP 1 LAST CUSTOM_TXT_CDS <CON_LAST_MODIFIED>
J 0
(2765 -1410);
DISPLAY 0.978723 (2765 -1410);
FORCEPROP 2 LAST CUSTOM_TXT_CDS <XR_PAGE_TITLE>
J 0
(-3240 3825);
DISPLAY 0.638298 (-3240 3825);
PAINT PINK (-3240 3825);
DISPLAY INVISIBLE (-3240 3825);
FORCEPROP 1 LAST CUSTOM_TXT_CDS <NAME_2>
J 0
(1475 -1375);
FORCEPROP 1 LAST CUSTOM_TXT_CDS <NAME_1>
J 0
(1475 -1250);
FORCEPROP 1 LAST CUSTOM_TXT_CDS <Q_NUMBER>
J 0
(3247 -1322);
DISPLAY 1.212766 (3247 -1322);
FORCEPROP 1 LAST CUSTOM_TXT_CDS <Q_PROJ>
J 0
(2268 -1323);
DISPLAY 1.212766 (2268 -1323);
FORCEPROP 1 LAST CUSTOM_TXT_CDS <Q_REV>
J 0
(4466 -1322);
DISPLAY 1.212766 (4466 -1322);
FORCEPROP 1 LAST CUSTOM_TXT_CDS <CON_PAGE_NUM> OF <CON_TOTAL_PAGES>
J 0
(4204 -1407);
DISPLAY 0.978723 (4204 -1407);
FORCEPROP 1 LAST Q_TITLE RESET CIRCUIT
J 0
(-4716 -1399);
DISPLAY 2.446809 (-4716 -1399);
PAINT GREEN (-4716 -1399);
FORCEPROP 2 LAST CDS_LIB pure_quanta
J 0
(4650 -1425);
DISPLAY INVISIBLE (4650 -1425);
FORCEPROP 1 LAST CDS_LMAN_SYM_OUTLINE -9475,6775,100,-125
J 0
(4650 -1425);
DISPLAY 0.468085 (4650 -1425);
PAINT GREEN (4650 -1425);
DISPLAY INVISIBLE (4650 -1425);
FORCEPROP 2 LAST PAGE_BORDER TRUE
J 0
(-3240 3825);
DISPLAY 0.638298 (-3240 3825);
PAINT PINK (-3240 3825);
DISPLAY INVISIBLE (-3240 3825);
FORCEPROP 1 LAST COMMENT_BODY TRUE
J 0
(4662 -1438);
DISPLAY 0.978723 (4662 -1438);
PAINT PEACH (4662 -1438);
DISPLAY INVISIBLE (4662 -1438);
FORCEPROP 2 LAST CDS_XR_PAGE_TITLE CR-22 : @SCM_LIB.SCM(SCH_1):PAGE22
J 0
(-3240 3825);
DISPLAY 0.638298 (-3240 3825);
PAINT PINK (-3240 3825);
DISPLAY INVISIBLE (-3240 3825);
FORCEADD DNS..1
(1350 750);
PAINT RED (1350 750);
FORCEPROP 2 LAST CDS_LIB mstr_misc
J 0
(1350 750);
DISPLAY INVISIBLE (1350 750);
FORCEPROP 1 LAST COMMENT_BODY TRUE
R 1
J 0
(1425 525);
DISPLAY 0.872340 (1425 525);
PAINT PEACH (1425 525);
DISPLAY INVISIBLE (1425 525);
FORCEADD DNS..1
(-1650 3075);
PAINT RED (-1650 3075);
FORCEPROP 2 LAST CDS_LIB mstr_misc
J 0
(-1650 3075);
DISPLAY INVISIBLE (-1650 3075);
FORCEPROP 1 LAST COMMENT_BODY TRUE
R 1
J 0
(-1575 2850);
DISPLAY 0.872340 (-1575 2850);
PAINT PEACH (-1575 2850);
DISPLAY INVISIBLE (-1575 2850);
FORCEADD DNS..1
(3850 2550);
PAINT RED (3850 2550);
FORCEPROP 1 LAST COMMENT_BODY TRUE
R 1
J 0
(3925 2325);
DISPLAY 0.872340 (3925 2325);
PAINT PEACH (3925 2325);
DISPLAY INVISIBLE (3925 2325);
FORCEPROP 2 LAST CDS_LIB mstr_misc
J 0
(3850 2550);
DISPLAY INVISIBLE (3850 2550);
FORCEADD DNS..1
(2900 2125);
PAINT RED (2900 2125);
FORCEPROP 1 LAST COMMENT_BODY TRUE
R 1
J 0
(2975 1900);
DISPLAY 0.872340 (2975 1900);
PAINT PEACH (2975 1900);
DISPLAY INVISIBLE (2975 1900);
FORCEPROP 2 LAST CDS_LIB mstr_misc
J 0
(2900 2125);
DISPLAY INVISIBLE (2900 2125);
FORCEADD DNS..1
(-2050 3625);
PAINT RED (-2050 3625);
FORCEPROP 1 LAST COMMENT_BODY TRUE
R 1
J 0
(-1975 3400);
DISPLAY 0.872340 (-1975 3400);
PAINT PEACH (-1975 3400);
DISPLAY INVISIBLE (-1975 3400);
FORCEPROP 2 LAST CDS_LIB mstr_misc
J 0
(-2050 3625);
DISPLAY INVISIBLE (-2050 3625);
FORCEADD DNS..2
(-2425 1825);
PAINT RED (-2425 1825);
FORCEPROP 2 LAST CDS_LIB mstr_misc
J 0
(-2425 1825);
DISPLAY INVISIBLE (-2425 1825);
FORCEPROP 1 LAST COMMENT_BODY TRUE
R 1
J 0
(-2350 1600);
DISPLAY 0.872340 (-2350 1600);
PAINT PEACH (-2350 1600);
DISPLAY INVISIBLE (-2350 1600);
FORCEADD DNS..1
(1600 2125);
PAINT RED (1600 2125);
FORCEPROP 1 LAST COMMENT_BODY TRUE
R 1
J 0
(1675 1900);
DISPLAY 0.872340 (1675 1900);
PAINT PEACH (1675 1900);
DISPLAY INVISIBLE (1675 1900);
FORCEPROP 2 LAST CDS_LIB mstr_misc
J 0
(1600 2125);
DISPLAY INVISIBLE (1600 2125);
FORCEADD DNS..1
(-3675 3300);
PAINT RED (-3675 3300);
FORCEPROP 1 LAST COMMENT_BODY TRUE
R 1
J 0
(-3600 3075);
DISPLAY 0.872340 (-3600 3075);
PAINT PEACH (-3600 3075);
DISPLAY INVISIBLE (-3600 3075);
FORCEPROP 2 LAST CDS_LIB mstr_misc
J 0
(-3675 3300);
DISPLAY INVISIBLE (-3675 3300);
FORCEADD DNS..1
(-4025 2375);
PAINT RED (-4025 2375);
FORCEPROP 2 LAST CDS_LIB mstr_misc
J 0
(-4025 2375);
DISPLAY INVISIBLE (-4025 2375);
FORCEPROP 1 LAST COMMENT_BODY TRUE
R 1
J 0
(-3950 2150);
DISPLAY 0.872340 (-3950 2150);
PAINT PEACH (-3950 2150);
DISPLAY INVISIBLE (-3950 2150);
WIRE 16 -1 (-550 425)(-550 375);
WIRE 16 -1 (-3750 3375)(-3750 3425);
WIRE 16 -1 (-1725 3150)(-1725 3200);
WIRE 16 -1 (225 4600)(225 4775);
WIRE 16 -1 (225 4600)(4000 4600);
WIRE 16 -1 (225 4500)(225 4600);
WIRE 16 -1 (3700 2775)(3700 2725);
WIRE 16 -1 (-2600 300)(-2600 475);
WIRE 16 -1 (-250 375)(-250 100);
WIRE 16 -1 (-575 4500)(-575 4650);
WIRE 16 -1 (1275 2625)(1275 2800);
WIRE 16 -1 (-2050 3250)(-2050 3325);
WIRE 16 -1 (-2050 3250)(-1925 3250);
WIRE 16 -1 (-2050 3225)(-2050 3250);
WIRE 16 -1 (-875 1875)(-875 1800);
WIRE 16 -1 (-4000 2475)(-4000 2500);
WIRE 16 -1 (-400 625)(-400 -225);
WIRE 16 -1 (-2000 625)(-2000 525);
WIRE 16 -1 (-1725 800)(-1725 1050);
WIRE 16 -1 (-675 1550)(-675 1475);
WIRE 16 -1 (-575 3875)(-575 3925);
WIRE 16 -1 (2400 1875)(2400 2025);
WIRE 16 -1 (-875 125)(-875 50);
WIRE 16 -1 (3875 2400)(3875 2450);
WIRE 16 -1 (-1550 -575)(-1550 -675);
WIRE 16 -1 (-1550 -225)(-1550 -575);
WIRE 16 -1 (-250 -575)(-1550 -575);
WIRE 16 -1 (1275 625)(1275 675);
WIRE 16 -1 (700 2350)(700 2675);
WIRE 16 -1 (225 3400)(225 3650);
WIRE 16 -1 (-175 2450)(-175 2350);
WIRE 16 -1 (-975 2500)(-975 2400);
WIRE 16 -1 (-2050 3025)(-2050 2950);
WIRE 16 -1 (-3025 2300)(-3025 2200);
WIRE 16 -1 (325 2450)(325 2350);
WIRE 16 -1 (3875 2725)(3875 2650);
WIRE 16 -1 (3700 2725)(3875 2725);
WIRE 16 -1 (3700 2725)(3700 2225);
WIRE 16 -1 (3625 2225)(3700 2225);
WIRE 16 -1 (2400 2025)(2625 2025);
WIRE 16 -1 (-675 1800)(-675 1750);
WIRE 16 -1 (-875 1800)(-675 1800);
WIRE 16 -1 (-875 1800)(-875 1050);
WIRE 16 -1 (-950 1050)(-875 1050);
WIRE 16 -1 (-1725 1050)(-1600 1050);
WIRE 16 -1 (-550 -175)(-775 -175);
WIRE 16 -1 (-875 375)(-875 325);
WIRE 16 -1 (-550 -175)(-550 375);
WIRE 16 -1 (-550 375)(-875 375);
WIRE 16 -1 (-250 -525)(-250 -575);
WIRE 16 -1 (-1475 -225)(-1550 -225);
WIRE 16 -1 (4000 4600)(4000 4150);
WIRE 16 -1 (-1925 2650)(-1925 3250);
WIRE 16 -1 (-775 -225)(-400 -225);
WIRE 16 -1 (-775 -275)(-250 -275);
FORCEPROP 2 LAST SIG_NAME U43_CT
J 0
(-510 -265);
DISPLAY 0.808511 (-510 -265);
WIRE 16 -1 (-250 -275)(-250 -325);
WIRE 16 -1 (-250 -100)(-250 -275);
WIRE 16 -1 (1450 2125)(1275 2125);
WIRE 16 -1 (1275 2425)(1275 2125);
WIRE 16 -1 (1275 1425)(2975 1425);
FORCEPROP 2 LAST SIG_NAME RST_BMC_SRST_BUF_R_N
J 0
(1440 1435);
DISPLAY 0.808511 (1440 1435);
WIRE 16 -1 (1275 1425)(1275 2125);
WIRE 16 -1 (1275 875)(1275 1100);
WIRE 16 -1 (1275 1100)(1275 1425);
WIRE 16 -1 (550 1100)(900 1100);
WIRE 16 -1 (900 1100)(1275 1100);
WIRE 16 -1 (900 1000)(900 1100);
WIRE 16 -1 (550 1000)(900 1000);
WIRE 16 -1 (4000 3950)(4000 3750);
WIRE 16 -1 (3325 3750)(4000 3750);
WIRE 16 -1 (700 2975)(700 3125);
WIRE 16 -1 (700 3125)(4000 3125);
FORCEPROP 2 LAST SIG_NAME RST_BMC_EXTRST_R1_N
J 0
(1965 3160);
DISPLAY 0.808511 (1965 3160);
WIRE 16 -1 (4000 3125)(4000 3750);
WIRE 16 -1 (4175 3125)(4000 3125);
WIRE 16 -1 (4175 3125)(4175 2025);
WIRE 16 -1 (3625 2025)(4175 2025);
WIRE 16 -1 (375 3750)(3125 3750);
FORCEPROP 2 LAST SIG_NAME BJT_Q3_B
J 0
(515 3760);
DISPLAY 0.851064 (515 3760);
WIRE 16 -1 (-950 1100)(350 1100);
FORCEPROP 2 LAST SIG_NAME PWRGD_P1V0_AUX_DELAY_BUF
J 0
(-810 1110);
DISPLAY 0.808511 (-810 1110);
WIRE 16 -1 (-950 1000)(350 1000);
FORCEPROP 2 LAST SIG_NAME RST_SRST_PLD_BMC_BUF_N
J 0
(-810 1010);
DISPLAY 0.808511 (-810 1010);
WIRE 16 -1 (-2975 1000)(-2000 1000);
FORCEPROP 2 LAST SIG_NAME RST_SRST_PLD_BMC_R1_N
J 0
(-2685 1010);
DISPLAY 0.851064 (-2685 1010);
WIRE 16 -1 (-1600 1000)(-2000 1000);
WIRE 16 -1 (-2000 825)(-2000 1000);
WIRE 16 -1 (-1725 1100)(-1600 1100);
WIRE 16 -1 (-3475 1425)(-1725 1425);
FORCEPROP 2 LAST SIG_NAME PWRGD_P1V0_AUX_DELAY
J 0
(-3425 1435);
DISPLAY 0.808511 (-3425 1435);
WIRE 16 -1 (-1725 1425)(-1725 1100);
WIRE 16 -1 (-1725 1800)(-1725 1425);
WIRE 16 -1 (-2325 1800)(-1725 1800);
WIRE 16 -1 (-4375 2850)(-3750 2850);
FORCEPROP 2 LAST SIG_NAME RST_BMC_SELF_HW
J 0
(-4385 2860);
DISPLAY 0.851064 (-4385 2860);
WIRE 16 -1 (-3750 2850)(-3700 2850);
WIRE 16 -1 (-3750 3175)(-3750 2850);
WIRE 16 -1 (-3025 2450)(-3700 2450);
FORCEPROP 2 LAST SIG_NAME RST_BMC_HW_R1
J 0
(-3660 2460);
DISPLAY 0.851064 (-3660 2460);
WIRE 16 3135 (-2050 2825)(-2925 2825);
WIRE 16 3135 (-2050 2125)(-2050 2825);
WIRE 16 3135 (-2925 2825)(-2925 2125);
WIRE 16 3135 (-2925 2125)(-2050 2125);
WIRE 16 -1 (-1925 2300)(-1225 2300);
FORCEPROP 2 LAST SIG_NAME RST_BMC_HW_OUT
J 0
(-1785 2310);
DISPLAY 0.851064 (-1785 2310);
WIRE 16 -1 (-1225 2575)(-1225 2300);
WIRE 16 -1 (-1725 2575)(-1225 2575);
WIRE 16 -1 (-1725 2775)(-1725 2575);
WIRE 16 -1 (-1725 2775)(-1525 2775);
WIRE 16 -1 (-1725 2950)(-1725 2775);
WIRE 16 -1 (-350 2775)(-175 2775);
FORCEPROP 2 LAST SIG_NAME RST_BMC_SELF_HW_D_C
J 0
(-310 2785);
DISPLAY 0.851064 (-310 2785);
WIRE 16 -1 (-175 2650)(-175 2775);
WIRE 16 -1 (-175 2775)(325 2775);
WIRE 16 -1 (325 2775)(550 2775);
WIRE 16 -1 (325 2650)(325 2775);
WIRE 16 -1 (-1275 2775)(-975 2775);
FORCEPROP 2 LAST SIG_NAME RST_BMC_SELF_HW_D
J 0
(-1235 2785);
DISPLAY 0.851064 (-1235 2785);
WIRE 16 -1 (-975 2775)(-550 2775);
WIRE 16 -1 (-975 2700)(-975 2775);
WIRE 16 -1 (-4425 2250)(-4000 2250);
FORCEPROP 2 LAST SIG_NAME RST_BMC_HW
J 0
(-4460 2260);
DISPLAY 0.851064 (-4460 2260);
WIRE 16 -1 (-4000 2250)(-3700 2250);
WIRE 16 -1 (-4000 2275)(-4000 2250);
WIRE 16 -1 (-3700 2650)(-3025 2650);
FORCEPROP 2 LAST SIG_NAME RST_BMC_SELF_HW_R3
J 0
(-3660 2660);
DISPLAY 0.851064 (-3660 2660);
WIRE 16 -1 (-3175 1000)(-4150 1000);
FORCEPROP 2 LAST SIG_NAME RST_SRST_PLD_BMC_R_N
J 0
(-4100 1010);
DISPLAY 0.808511 (-4100 1010);
WIRE 16 -1 (-3475 1800)(-2525 1800);
FORCEPROP 2 LAST SIG_NAME PWRGD_PSU_AC_PWROK
J 0
(-3435 1810);
DISPLAY 0.808511 (-3435 1810);
WIRE 16 -1 (-1475 -175)(-2600 -175);
FORCEPROP 2 LAST SIG_NAME PWRGD_P1V0_AUX_DELAY_R1
J 0
(-2560 -140);
DISPLAY 0.808511 (-2560 -140);
WIRE 16 -1 (-2600 100)(-2600 -175);
WIRE 16 -1 (-2875 -175)(-2600 -175);
WIRE 16 -1 (-2875 -275)(-1475 -275);
FORCEPROP 2 LAST SIG_NAME PWRGD_P1V0_AUX_R2
J 0
(-2560 -265);
DISPLAY 0.808511 (-2560 -265);
WIRE 16 -1 (-425 4025)(225 4025);
FORCEPROP 2 LAST SIG_NAME BJT_Q3_C
J 0
(-260 4035);
DISPLAY 0.851064 (-260 4035);
WIRE 16 -1 (225 4025)(225 3850);
WIRE 16 -1 (225 4025)(225 4300);
WIRE 16 -1 (-2775 4200)(-2125 4200);
FORCEPROP 2 LAST SIG_NAME RST_EXTRST_N
J 0
(-2760 4210);
DISPLAY 0.808511 (-2760 4210);
WIRE 16 -1 (3175 1425)(4050 1425);
FORCEPROP 2 LAST SIG_NAME RST_BMC_SRST_N
J 0
(3290 1435);
DISPLAY 0.808511 (3290 1435);
WIRE 16 -1 (-1925 3650)(-1450 3650);
WIRE 16 -1 (-575 4125)(-575 4200);
WIRE 16 -1 (-575 4200)(-575 4300);
WIRE 16 -1 (-1925 4200)(-1450 4200);
FORCEPROP 2 LAST SIG_NAME RST_BMC_EXTRST_R2_N
J 0
(-1710 4210);
DISPLAY 0.808511 (-1710 4210);
WIRE 16 -1 (-1450 3650)(-1450 4200);
WIRE 16 -1 (-1450 4200)(-875 4200);
WIRE 16 -1 (-875 4200)(-575 4200);
WIRE 16 -1 (-875 4650)(-2825 4650);
WIRE 16 -1 (-875 4650)(-875 4200);
WIRE 16 -1 (-4200 -175)(-3075 -175);
FORCEPROP 0 LAST SIG_NAME PWRGD_P1V0_AUX_DELAY
J 0
(-4185 -165);
DISPLAY 0.808511 (-4185 -165);
WIRE 16 -1 (-4200 -275)(-3075 -275);
FORCEPROP 0 LAST SIG_NAME PWRGD_P1V0_AUX
J 0
(-4185 -265);
DISPLAY 0.808511 (-4185 -265);
WIRE 16 -1 (-2775 3650)(-2125 3650);
FORCEPROP 2 LAST SIG_NAME RST_BMC_SRST_N
J 0
(-2760 3660);
DISPLAY 0.808511 (-2760 3660);
WIRE 16 -1 (1650 2125)(2625 2125);
FORCEPROP 2 LAST SIG_NAME RST_BMC_SRST_BUF_R1_N
J 0
(1765 2135);
DISPLAY 0.808511 (1765 2135);
DOT 1 (900 1100);
DOT 1 (325 2775);
DOT 1 (-175 2775);
DOT 1 (-550 375);
DOT 1 (-575 4200);
DOT 1 (225 4600);
DOT 1 (-250 -275);
DOT 1 (4000 3750);
DOT 1 (4000 3125);
DOT 1 (-875 4200);
DOT 1 (-1450 4200);
DOT 1 (-2600 -175);
DOT 1 (3700 2725);
DOT 1 (-2000 1000);
DOT 1 (-1550 -575);
DOT 1 (225 4025);
DOT 1 (-875 1800);
DOT 1 (1275 2125);
DOT 1 (1275 1425);
DOT 1 (1275 1100);
DOT 1 (-975 2775);
DOT 1 (-2050 3250);
DOT 1 (-1725 1425);
DOT 1 (-1725 2775);
DOT 1 (-3750 2850);
DOT 1 (-4000 2250);
FORCENOTE
ADD U58_20221206
(-2000 2175) 0;
DISPLAY LEFT (-2000 2175);
DISPLAY 1.276596 (-2000 2175);
PAINT VIOLET (-2000 2175);
FORCENOTE
OPEN-DRAIN
(-1525 825) 0;
DISPLAY LEFT (-1525 825);
DISPLAY 1.276596 (-1525 825);
FORCENOTE
DAMPING RES SHOULD CLOSE TO BUFFER
(-725 1225) 0;
DISPLAY LEFT (-725 1225);
DISPLAY 1.021277 (-725 1225);
FORCENOTE
FROM CPLD FOR SRST#
(-4500 1075) 0;
DISPLAY LEFT (-4500 1075);
DISPLAY 2.510638 (-4500 1075);
PAINT RED (-4500 1075);
FORCENOTE
FROM DELAY IC FOR VR PG
(-4525 1525) 0;
DISPLAY LEFT (-4525 1525);
DISPLAY 2.510638 (-4525 1525);
PAINT RED (-4525 1525);
FORCENOTE
FROM PWRGD_PSU_AC_PWROK
(-4500 1925) 0;
DISPLAY LEFT (-4500 1925);
DISPLAY 2.510638 (-4500 1925);
PAINT RED (-4500 1925);
FORCENOTE
TO BMC (SRST_N)
(-4425 3825) 0;
DISPLAY LEFT (-4425 3825);
DISPLAY 2.510638 (-4425 3825);
PAINT RED (-4425 3825);
FORCENOTE
FROM BMC WDTRST1#
(-4550 2975) 0;
DISPLAY LEFT (-4550 2975);
DISPLAY 2.000000 (-4550 2975);
PAINT RED (-4550 2975);
FORCENOTE
FROM CPLD
(-4650 2450) 0;
DISPLAY LEFT (-4650 2450);
DISPLAY 2.000000 (-4650 2450);
PAINT RED (-4650 2450);
FORCENOTE
OPEN-DRAIN
(-1375 -475) 0;
DISPLAY LEFT (-1375 -475);
DISPLAY 1.276596 (-1375 -475);
FORCENOTE
TO BMC TPM
(-4325 4750) 0;
DISPLAY LEFT (-4325 4750);
DISPLAY 2.510638 (-4325 4750);
PAINT RED (-4325 4750);
FORCENOTE
OPEN-DRAIN
(2500 1800) 0;
DISPLAY LEFT (2500 1800);
DISPLAY 1.276596 (2500 1800);
PAINT RED (2500 1800);
FORCENOTE
TO BMC (SRST_N)
(2125 1550) 0;
DISPLAY LEFT (2125 1550);
DISPLAY 2.510638 (2125 1550);
PAINT RED (2125 1550);
FORCENOTE
TO BMC (EXTRST_N)
(-4425 4350) 0;
DISPLAY LEFT (-4425 4350);
DISPLAY 2.510638 (-4425 4350);
PAINT RED (-4425 4350);
FORCENOTE
$CDS_IMAGE|clipboard_0_1_SI5.jpg|2500|500
(3075 -250) 0;
DISPLAY LEFT (3075 -250);
QUIT
